G04 ================== begin FILE IDENTIFICATION RECORD ==================*
G04 Layout Name:  D:/<user>/Wistron_project/16317-1/gbr/16317-1.brd*
G04 Film Name:    SE_REF_L1*
G04 File Format:  Gerber RS274X*
G04 File Origin:  Cadence Allegro 16.5-S056*
G04 Origin Date:  Fri Jun 09 15:53:55 2017*
G04 *
G04 Layer:  BOARD GEOMETRY/SE_REF_L1_TBL*
G04 Layer:  BOARD GEOMETRY/SE_REF_L1_TOP*
G04 Layer:  BOARD GEOMETRY/PANEL_OUTLINE*
G04 *
G04 Offset:    (0.00 0.00)*
G04 Mirror:    No*
G04 Mode:      Positive*
G04 Rotation:  0*
G04 FullContactRelief:  No*
G04 UndefLineWidth:     6.00*
G04 ================== end FILE IDENTIFICATION RECORD ====================*
%FSLAX35Y35*MOIN*%
%IR0*IPPOS*OFA0.00000B0.00000*MIA0B0*SFA1.00000B1.00000*%
%ADD10C,.02*%
%ADD11C,.006*%
%ADD12C,.00675*%
G75*
%LPD*%
G75*
G54D10*
G01X1985143Y1416035D02*
X2702643D01*
G01X1985143Y1485335D02*
Y1416035D01*
G01Y1485335D02*
X2702643D01*
G01X1985143Y1450685D02*
X2702643D01*
G01X2160143Y1485335D02*
Y1416035D01*
G01X2387643Y1485335D02*
Y1416035D01*
G01X2492643Y1485335D02*
Y1416035D01*
G01X2702643Y1485335D02*
Y1416035D01*
G54D11*
G01X6250Y-33194D02*
Y-50694D01*
G01X1228Y-33194D02*
X11272D01*
G01X20038Y-50694D02*
Y-33194D01*
G01Y-41652D02*
X21130Y-40194D01*
X22222Y-39319D01*
X23968Y-39028D01*
X25278Y-39319D01*
X26807Y-40486D01*
X27462Y-42236D01*
Y-50694D01*
G01X41250Y-39028D02*
Y-50694D01*
G01Y-34361D02*
X40813Y-34069D01*
Y-33486D01*
X41250Y-33194D01*
X41687Y-33486D01*
Y-34069D01*
X41250Y-34361D01*
G01X55475Y-48653D02*
X56567Y-49819D01*
X58095Y-50694D01*
X59405D01*
X60715Y-50111D01*
X61588Y-49236D01*
X62025Y-48070D01*
X61807Y-46319D01*
X60933Y-45444D01*
X57003Y-43694D01*
X56130Y-41652D01*
X56567Y-40194D01*
X57440Y-39319D01*
X58750Y-39028D01*
X60060Y-39319D01*
X61370Y-40194D01*
G01X90693Y-55069D02*
X92222Y-56236D01*
X93968Y-56527D01*
X95496Y-56236D01*
X96807Y-54778D01*
X97680Y-52736D01*
Y-39028D01*
G01Y-41361D02*
X96807Y-40194D01*
X95496Y-39319D01*
X93968Y-39028D01*
X92222Y-39611D01*
X91130Y-40777D01*
X90256Y-42819D01*
X89820Y-44861D01*
X90038Y-46611D01*
X90912Y-48653D01*
X92222Y-50111D01*
X93968Y-50694D01*
X95278Y-50402D01*
X96807Y-49236D01*
X97680Y-48070D01*
G01X107975Y-42819D02*
X114962D01*
X114307Y-40777D01*
X113215Y-39611D01*
X111687Y-39028D01*
X110158Y-39319D01*
X108848Y-40194D01*
X107975Y-42236D01*
X107538Y-43986D01*
Y-45736D01*
X107975Y-47486D01*
X109067Y-49236D01*
X110377Y-50402D01*
X111905Y-50694D01*
X113433Y-50111D01*
X114962Y-48361D01*
G01X125693Y-50694D02*
Y-39028D01*
G01Y-41361D02*
X126785Y-40194D01*
X127877Y-39319D01*
X129405Y-39028D01*
X130496Y-39319D01*
X131807Y-40194D01*
G01X142320Y-50694D02*
Y-33194D01*
G01Y-41944D02*
X143412Y-40194D01*
X144722Y-39319D01*
X146032Y-39028D01*
X147996Y-39611D01*
X149307Y-40777D01*
X150180Y-42819D01*
Y-45152D01*
X149743Y-47486D01*
X148870Y-49236D01*
X147342Y-50402D01*
X146032Y-50694D01*
X144722Y-50402D01*
X143412Y-49528D01*
X142320Y-48070D01*
G01X160475Y-42819D02*
X167462D01*
X166807Y-40777D01*
X165715Y-39611D01*
X164187Y-39028D01*
X162658Y-39319D01*
X161348Y-40194D01*
X160475Y-42236D01*
X160038Y-43986D01*
Y-45736D01*
X160475Y-47486D01*
X161567Y-49236D01*
X162877Y-50402D01*
X164405Y-50694D01*
X165933Y-50111D01*
X167462Y-48361D01*
G01X178193Y-50694D02*
Y-39028D01*
G01Y-41361D02*
X179285Y-40194D01*
X180377Y-39319D01*
X181905Y-39028D01*
X182996Y-39319D01*
X184307Y-40194D01*
G01X216250Y-39028D02*
Y-50694D01*
G01Y-34361D02*
X215813Y-34069D01*
Y-33486D01*
X216250Y-33194D01*
X216687Y-33486D01*
Y-34069D01*
X216250Y-34361D01*
G01X230475Y-48653D02*
X231567Y-49819D01*
X233095Y-50694D01*
X234405D01*
X235715Y-50111D01*
X236588Y-49236D01*
X237025Y-48070D01*
X236807Y-46319D01*
X235933Y-45444D01*
X232003Y-43694D01*
X231130Y-41652D01*
X231567Y-40194D01*
X232440Y-39319D01*
X233750Y-39028D01*
X235060Y-39319D01*
X236370Y-40194D01*
G01X265256Y-55069D02*
X266785Y-56236D01*
X268095Y-56527D01*
X269842Y-55944D01*
X271152Y-54486D01*
X271807Y-51860D01*
Y-39028D01*
G01Y-34361D02*
X271370Y-34069D01*
Y-33486D01*
X271807Y-33194D01*
X272243Y-33486D01*
Y-34069D01*
X271807Y-34361D01*
G01X282538Y-39028D02*
Y-47194D01*
X283412Y-49236D01*
X284722Y-50402D01*
X286250Y-50694D01*
X287778Y-50402D01*
X289088Y-49236D01*
X289962Y-47194D01*
G01Y-50694D02*
Y-39028D01*
G01X300475Y-48653D02*
X301567Y-49819D01*
X303095Y-50694D01*
X304405D01*
X305715Y-50111D01*
X306588Y-49236D01*
X307025Y-48070D01*
X306807Y-46319D01*
X305933Y-45444D01*
X302003Y-43694D01*
X301130Y-41652D01*
X301567Y-40194D01*
X302440Y-39319D01*
X303750Y-39028D01*
X305060Y-39319D01*
X306370Y-40194D01*
G01X321250Y-33194D02*
Y-50694D01*
G01X318193Y-39028D02*
X324307D01*
G01X354940Y-50694D02*
Y-35819D01*
X355377Y-34361D01*
X356250Y-33486D01*
X357560Y-33194D01*
X358870Y-33777D01*
X359525Y-35236D01*
G01X356905Y-40194D02*
X352538D01*
G01X373750Y-50694D02*
X372440Y-50402D01*
X371130Y-49236D01*
X370256Y-47194D01*
X369820Y-44861D01*
X370256Y-42527D01*
X371130Y-40486D01*
X372440Y-39319D01*
X373750Y-39028D01*
X375060Y-39319D01*
X376370Y-40486D01*
X377243Y-42527D01*
X377462Y-44861D01*
X377243Y-47194D01*
X376370Y-49236D01*
X375060Y-50402D01*
X373750Y-50694D01*
G01X388193D02*
Y-39028D01*
G01Y-41361D02*
X389285Y-40194D01*
X390377Y-39319D01*
X391905Y-39028D01*
X392996Y-39319D01*
X394307Y-40194D01*
G01X421665Y-55944D02*
X422975Y-56527D01*
X424722Y-55944D01*
X425813Y-54778D01*
X426687Y-53319D01*
X427996Y-48653D01*
X430835Y-39028D01*
G01X423848D02*
X427996Y-48653D01*
G01X443750Y-50694D02*
X442440Y-50402D01*
X441130Y-49236D01*
X440256Y-47194D01*
X439820Y-44861D01*
X440256Y-42527D01*
X441130Y-40486D01*
X442440Y-39319D01*
X443750Y-39028D01*
X445060Y-39319D01*
X446370Y-40486D01*
X447243Y-42527D01*
X447462Y-44861D01*
X447243Y-47194D01*
X446370Y-49236D01*
X445060Y-50402D01*
X443750Y-50694D01*
G01X457538Y-39028D02*
Y-47194D01*
X458412Y-49236D01*
X459722Y-50402D01*
X461250Y-50694D01*
X462778Y-50402D01*
X464088Y-49236D01*
X464962Y-47194D01*
G01Y-50694D02*
Y-39028D01*
G01X475693Y-50694D02*
Y-39028D01*
G01Y-41361D02*
X476785Y-40194D01*
X477877Y-39319D01*
X479405Y-39028D01*
X480496Y-39319D01*
X481807Y-40194D01*
G01X510693Y-50694D02*
Y-39028D01*
G01Y-41361D02*
X511785Y-40194D01*
X512877Y-39319D01*
X514405Y-39028D01*
X515496Y-39319D01*
X516807Y-40194D01*
G01X527975Y-42819D02*
X534962D01*
X534307Y-40777D01*
X533215Y-39611D01*
X531687Y-39028D01*
X530158Y-39319D01*
X528848Y-40194D01*
X527975Y-42236D01*
X527538Y-43986D01*
Y-45736D01*
X527975Y-47486D01*
X529067Y-49236D01*
X530377Y-50402D01*
X531905Y-50694D01*
X533433Y-50111D01*
X534962Y-48361D01*
G01X547440Y-50694D02*
Y-35819D01*
X547877Y-34361D01*
X548750Y-33486D01*
X550060Y-33194D01*
X551370Y-33777D01*
X552025Y-35236D01*
G01X549405Y-40194D02*
X545038D01*
G01X562975Y-42819D02*
X569962D01*
X569307Y-40777D01*
X568215Y-39611D01*
X566687Y-39028D01*
X565158Y-39319D01*
X563848Y-40194D01*
X562975Y-42236D01*
X562538Y-43986D01*
Y-45736D01*
X562975Y-47486D01*
X564067Y-49236D01*
X565377Y-50402D01*
X566905Y-50694D01*
X568433Y-50111D01*
X569962Y-48361D01*
G01X580693Y-50694D02*
Y-39028D01*
G01Y-41361D02*
X581785Y-40194D01*
X582877Y-39319D01*
X584405Y-39028D01*
X585496Y-39319D01*
X586807Y-40194D01*
G01X597975Y-42819D02*
X604962D01*
X604307Y-40777D01*
X603215Y-39611D01*
X601687Y-39028D01*
X600158Y-39319D01*
X598848Y-40194D01*
X597975Y-42236D01*
X597538Y-43986D01*
Y-45736D01*
X597975Y-47486D01*
X599067Y-49236D01*
X600377Y-50402D01*
X601905Y-50694D01*
X603433Y-50111D01*
X604962Y-48361D01*
G01X615038Y-50694D02*
Y-39028D01*
G01Y-41944D02*
X615912Y-40486D01*
X617222Y-39319D01*
X618968Y-39028D01*
X620496Y-39319D01*
X621807Y-40486D01*
X622462Y-42527D01*
Y-50694D01*
G01X639743Y-40486D02*
X638215Y-39319D01*
X636905Y-39028D01*
X635158Y-39611D01*
X633848Y-40777D01*
X632975Y-42819D01*
X632756Y-44861D01*
X632975Y-46903D01*
X633848Y-48653D01*
X635158Y-50111D01*
X636905Y-50694D01*
X638433Y-50111D01*
X639743Y-48944D01*
G01X650475Y-42819D02*
X657462D01*
X656807Y-40777D01*
X655715Y-39611D01*
X654187Y-39028D01*
X652658Y-39319D01*
X651348Y-40194D01*
X650475Y-42236D01*
X650038Y-43986D01*
Y-45736D01*
X650475Y-47486D01*
X651567Y-49236D01*
X652877Y-50402D01*
X654405Y-50694D01*
X655933Y-50111D01*
X657462Y-48361D01*
G01X688750Y-33194D02*
Y-50694D01*
G01X685693Y-39028D02*
X691807D01*
G01X706250Y-50694D02*
X704940Y-50402D01*
X703630Y-49236D01*
X702756Y-47194D01*
X702320Y-44861D01*
X702756Y-42527D01*
X703630Y-40486D01*
X704940Y-39319D01*
X706250Y-39028D01*
X707560Y-39319D01*
X708870Y-40486D01*
X709743Y-42527D01*
X709962Y-44861D01*
X709743Y-47194D01*
X708870Y-49236D01*
X707560Y-50402D01*
X706250Y-50694D01*
G01X739940D02*
Y-35819D01*
X740377Y-34361D01*
X741250Y-33486D01*
X742560Y-33194D01*
X743870Y-33777D01*
X744525Y-35236D01*
G01X741905Y-40194D02*
X737538D01*
G01X758750Y-39028D02*
Y-50694D01*
G01Y-34361D02*
X758313Y-34069D01*
Y-33486D01*
X758750Y-33194D01*
X759187Y-33486D01*
Y-34069D01*
X758750Y-34361D01*
G01X772538Y-50694D02*
Y-39028D01*
G01Y-41944D02*
X773412Y-40486D01*
X774722Y-39319D01*
X776468Y-39028D01*
X777996Y-39319D01*
X779307Y-40486D01*
X779962Y-42527D01*
Y-50694D01*
G01X797680Y-33194D02*
Y-50694D01*
G01Y-48070D02*
X796807Y-49528D01*
X795496Y-50402D01*
X793968Y-50694D01*
X792222Y-50111D01*
X790912Y-48653D01*
X790038Y-46903D01*
X789820Y-44861D01*
X790038Y-42819D01*
X790912Y-41069D01*
X792222Y-39611D01*
X793968Y-39028D01*
X795496Y-39319D01*
X796588Y-39903D01*
X797680Y-41069D01*
G01X828750Y-33194D02*
Y-50694D01*
G01X825693Y-39028D02*
X831807D01*
G01X842538Y-50694D02*
Y-33194D01*
G01Y-41652D02*
X843630Y-40194D01*
X844722Y-39319D01*
X846468Y-39028D01*
X847778Y-39319D01*
X849307Y-40486D01*
X849962Y-42236D01*
Y-50694D01*
G01X860475Y-42819D02*
X867462D01*
X866807Y-40777D01*
X865715Y-39611D01*
X864187Y-39028D01*
X862658Y-39319D01*
X861348Y-40194D01*
X860475Y-42236D01*
X860038Y-43986D01*
Y-45736D01*
X860475Y-47486D01*
X861567Y-49236D01*
X862877Y-50402D01*
X864405Y-50694D01*
X865933Y-50111D01*
X867462Y-48361D01*
G01X894165D02*
X895912Y-49819D01*
X897877Y-50694D01*
X899623D01*
X901370Y-49819D01*
X902680Y-48361D01*
X903335Y-46319D01*
X902898Y-44278D01*
X901807Y-42527D01*
X899842Y-41361D01*
X897222Y-40777D01*
X895693Y-39611D01*
X895038Y-37569D01*
X895475Y-35527D01*
X896567Y-34069D01*
X898095Y-33194D01*
X899623D01*
X901152Y-33777D01*
X902462Y-35236D01*
G01X920617Y-50694D02*
X911883D01*
Y-33194D01*
X920617D01*
G01X917123Y-41652D02*
X911883D01*
G01X951250Y-39028D02*
Y-50694D01*
G01Y-34361D02*
X950813Y-34069D01*
Y-33486D01*
X951250Y-33194D01*
X951687Y-33486D01*
Y-34069D01*
X951250Y-34361D01*
G01X962200Y-50694D02*
Y-39028D01*
G01Y-42236D02*
X962855Y-40777D01*
X963947Y-39611D01*
X965475Y-39028D01*
X967003Y-39611D01*
X968095Y-40777D01*
X968750Y-42236D01*
Y-50694D01*
G01Y-42236D02*
X969405Y-40777D01*
X970496Y-39611D01*
X972025Y-39028D01*
X973553Y-39611D01*
X974645Y-40777D01*
X975300Y-42527D01*
Y-50694D01*
G01X982320Y-56527D02*
Y-39028D01*
G01Y-41652D02*
X983412Y-40194D01*
X984503Y-39319D01*
X986250Y-39028D01*
X987778Y-39319D01*
X989307Y-40777D01*
X989962Y-42819D01*
X990180Y-44861D01*
X989962Y-46903D01*
X989307Y-48944D01*
X987996Y-50111D01*
X986250Y-50694D01*
X984722Y-50402D01*
X983193Y-49528D01*
X982320Y-48361D01*
G01X1000475Y-42819D02*
X1007462D01*
X1006807Y-40777D01*
X1005715Y-39611D01*
X1004187Y-39028D01*
X1002658Y-39319D01*
X1001348Y-40194D01*
X1000475Y-42236D01*
X1000038Y-43986D01*
Y-45736D01*
X1000475Y-47486D01*
X1001567Y-49236D01*
X1002877Y-50402D01*
X1004405Y-50694D01*
X1005933Y-50111D01*
X1007462Y-48361D01*
G01X1025180Y-33194D02*
Y-50694D01*
G01Y-48070D02*
X1024307Y-49528D01*
X1022996Y-50402D01*
X1021468Y-50694D01*
X1019722Y-50111D01*
X1018412Y-48653D01*
X1017538Y-46903D01*
X1017320Y-44861D01*
X1017538Y-42819D01*
X1018412Y-41069D01*
X1019722Y-39611D01*
X1021468Y-39028D01*
X1022996Y-39319D01*
X1024088Y-39903D01*
X1025180Y-41069D01*
G01X1042680Y-50694D02*
Y-39028D01*
G01Y-41069D02*
X1041807Y-39903D01*
X1040496Y-39319D01*
X1038968Y-39028D01*
X1037440Y-39611D01*
X1036130Y-40777D01*
X1035256Y-42527D01*
X1034820Y-44861D01*
X1035256Y-47194D01*
X1036130Y-48944D01*
X1037440Y-50111D01*
X1038968Y-50694D01*
X1040496Y-50402D01*
X1041807Y-49528D01*
X1042680Y-48361D01*
G01X1052538Y-50694D02*
Y-39028D01*
G01Y-41944D02*
X1053412Y-40486D01*
X1054722Y-39319D01*
X1056468Y-39028D01*
X1057996Y-39319D01*
X1059307Y-40486D01*
X1059962Y-42527D01*
Y-50694D01*
G01X1077243Y-40486D02*
X1075715Y-39319D01*
X1074405Y-39028D01*
X1072658Y-39611D01*
X1071348Y-40777D01*
X1070475Y-42819D01*
X1070256Y-44861D01*
X1070475Y-46903D01*
X1071348Y-48653D01*
X1072658Y-50111D01*
X1074405Y-50694D01*
X1075933Y-50111D01*
X1077243Y-48944D01*
G01X1087975Y-42819D02*
X1094962D01*
X1094307Y-40777D01*
X1093215Y-39611D01*
X1091687Y-39028D01*
X1090158Y-39319D01*
X1088848Y-40194D01*
X1087975Y-42236D01*
X1087538Y-43986D01*
Y-45736D01*
X1087975Y-47486D01*
X1089067Y-49236D01*
X1090377Y-50402D01*
X1091905Y-50694D01*
X1093433Y-50111D01*
X1094962Y-48361D01*
G01X1126250Y-33194D02*
Y-50694D01*
G01X1123193Y-39028D02*
X1129307D01*
G01X1140693Y-50694D02*
Y-39028D01*
G01Y-41361D02*
X1141785Y-40194D01*
X1142877Y-39319D01*
X1144405Y-39028D01*
X1145496Y-39319D01*
X1146807Y-40194D01*
G01X1165180Y-50694D02*
Y-39028D01*
G01Y-41069D02*
X1164307Y-39903D01*
X1162996Y-39319D01*
X1161468Y-39028D01*
X1159940Y-39611D01*
X1158630Y-40777D01*
X1157756Y-42527D01*
X1157320Y-44861D01*
X1157756Y-47194D01*
X1158630Y-48944D01*
X1159940Y-50111D01*
X1161468Y-50694D01*
X1162996Y-50402D01*
X1164307Y-49528D01*
X1165180Y-48361D01*
G01X1182243Y-40486D02*
X1180715Y-39319D01*
X1179405Y-39028D01*
X1177658Y-39611D01*
X1176348Y-40777D01*
X1175475Y-42819D01*
X1175256Y-44861D01*
X1175475Y-46903D01*
X1176348Y-48653D01*
X1177658Y-50111D01*
X1179405Y-50694D01*
X1180933Y-50111D01*
X1182243Y-48944D01*
G01X1192975Y-42819D02*
X1199962D01*
X1199307Y-40777D01*
X1198215Y-39611D01*
X1196687Y-39028D01*
X1195158Y-39319D01*
X1193848Y-40194D01*
X1192975Y-42236D01*
X1192538Y-43986D01*
Y-45736D01*
X1192975Y-47486D01*
X1194067Y-49236D01*
X1195377Y-50402D01*
X1196905Y-50694D01*
X1198433Y-50111D01*
X1199962Y-48361D01*
G01X1210475Y-48653D02*
X1211567Y-49819D01*
X1213095Y-50694D01*
X1214405D01*
X1215715Y-50111D01*
X1216588Y-49236D01*
X1217025Y-48070D01*
X1216807Y-46319D01*
X1215933Y-45444D01*
X1212003Y-43694D01*
X1211130Y-41652D01*
X1211567Y-40194D01*
X1212440Y-39319D01*
X1213750Y-39028D01*
X1215060Y-39319D01*
X1216370Y-40194D01*
G01X1248750Y-39028D02*
Y-50694D01*
G01Y-34361D02*
X1248313Y-34069D01*
Y-33486D01*
X1248750Y-33194D01*
X1249187Y-33486D01*
Y-34069D01*
X1248750Y-34361D01*
G01X1262538Y-50694D02*
Y-39028D01*
G01Y-41944D02*
X1263412Y-40486D01*
X1264722Y-39319D01*
X1266468Y-39028D01*
X1267996Y-39319D01*
X1269307Y-40486D01*
X1269962Y-42527D01*
Y-50694D01*
G01X1301250D02*
Y-33194D01*
G01X1322680Y-50694D02*
Y-39028D01*
G01Y-41069D02*
X1321807Y-39903D01*
X1320496Y-39319D01*
X1318968Y-39028D01*
X1317440Y-39611D01*
X1316130Y-40777D01*
X1315256Y-42527D01*
X1314820Y-44861D01*
X1315256Y-47194D01*
X1316130Y-48944D01*
X1317440Y-50111D01*
X1318968Y-50694D01*
X1320496Y-50402D01*
X1321807Y-49528D01*
X1322680Y-48361D01*
G01X1331665Y-55944D02*
X1332975Y-56527D01*
X1334722Y-55944D01*
X1335813Y-54778D01*
X1336687Y-53319D01*
X1337996Y-48653D01*
X1340835Y-39028D01*
G01X1333848D02*
X1337996Y-48653D01*
G01X1350475Y-42819D02*
X1357462D01*
X1356807Y-40777D01*
X1355715Y-39611D01*
X1354187Y-39028D01*
X1352658Y-39319D01*
X1351348Y-40194D01*
X1350475Y-42236D01*
X1350038Y-43986D01*
Y-45736D01*
X1350475Y-47486D01*
X1351567Y-49236D01*
X1352877Y-50402D01*
X1354405Y-50694D01*
X1355933Y-50111D01*
X1357462Y-48361D01*
G01X1368193Y-50694D02*
Y-39028D01*
G01Y-41361D02*
X1369285Y-40194D01*
X1370377Y-39319D01*
X1371905Y-39028D01*
X1372996Y-39319D01*
X1374307Y-40194D01*
G01X1401883Y-33194D02*
Y-50694D01*
X1410617D01*
G01X1423750D02*
Y-33194D01*
X1421130Y-36694D01*
G01Y-50694D02*
X1426370D01*
G01X1441250Y-51277D02*
X1440813Y-50986D01*
Y-50402D01*
X1441250Y-50111D01*
X1441687Y-50402D01*
Y-50986D01*
X1441250Y-51277D01*
G01X1987108Y1497418D02*
X1988855Y1495960D01*
X1990820Y1495085D01*
X1992566D01*
X1994313Y1495960D01*
X1995623Y1497418D01*
X1996278Y1499460D01*
X1995841Y1501501D01*
X1994750Y1503252D01*
X1992785Y1504418D01*
X1990165Y1505002D01*
X1988636Y1506168D01*
X1987981Y1508210D01*
X1988418Y1510252D01*
X1989510Y1511710D01*
X1991038Y1512585D01*
X1992566D01*
X1994095Y1512002D01*
X1995405Y1510543D01*
G01X2013560Y1495085D02*
X2004826D01*
Y1512585D01*
X2013560D01*
G01X2010066Y1504127D02*
X2004826D01*
G01X2041573Y1512585D02*
X2046813D01*
G01X2044193D02*
Y1495085D01*
G01X2041573D02*
X2046813D01*
G01X2056016D02*
Y1512585D01*
X2061693Y1498002D01*
X2067370Y1512585D01*
Y1495085D01*
G01X2074826D02*
Y1512585D01*
X2080066D01*
X2081813Y1511710D01*
X2083123Y1509668D01*
X2083560Y1507335D01*
X2083123Y1505002D01*
X2082031Y1503252D01*
X2080066Y1502376D01*
X2074826D01*
G01X2101060Y1495085D02*
X2092326D01*
Y1512585D01*
X2101060D01*
G01X2097566Y1504127D02*
X2092326D01*
G01X2109390Y1495085D02*
Y1512585D01*
X2113756D01*
X2115503Y1511710D01*
X2116813Y1510543D01*
X2117905Y1508794D01*
X2118778Y1506751D01*
X2118996Y1503835D01*
X2118778Y1500918D01*
X2117905Y1498876D01*
X2116813Y1497126D01*
X2115503Y1495960D01*
X2113756Y1495085D01*
X2109390D01*
G01X2126234D02*
X2131693Y1512585D01*
X2137152Y1495085D01*
G01X2135186Y1501210D02*
X2128199D01*
G01X2144171Y1495085D02*
Y1512585D01*
X2154215Y1495085D01*
Y1512585D01*
G01X2171496Y1511126D02*
X2170186Y1512002D01*
X2168658Y1512585D01*
X2166911D01*
X2164946Y1511710D01*
X2163418Y1510252D01*
X2162326Y1508501D01*
X2161453Y1505585D01*
X2161234Y1502960D01*
X2161671Y1500335D01*
X2162326Y1498585D01*
X2163636Y1496835D01*
X2165165Y1495668D01*
X2166693Y1495085D01*
X2168221D01*
X2169750Y1495668D01*
X2171060Y1496543D01*
X2172152Y1497709D01*
G01X2188560Y1495085D02*
X2179826D01*
Y1512585D01*
X2188560D01*
G01X2185066Y1504127D02*
X2179826D01*
G01X2219193Y1512585D02*
Y1495085D01*
G01X2214171Y1512585D02*
X2224215D01*
G01X2231234Y1495085D02*
X2236693Y1512585D01*
X2242152Y1495085D01*
G01X2240186Y1501210D02*
X2233199D01*
G01X2255939Y1504418D02*
X2256813Y1505293D01*
X2257468Y1506751D01*
X2257905Y1508794D01*
X2257468Y1510543D01*
X2256595Y1511710D01*
X2255066Y1512585D01*
X2249171D01*
Y1495085D01*
X2256376D01*
X2257905Y1496251D01*
X2258778Y1498002D01*
X2259215Y1500043D01*
X2258778Y1502085D01*
X2257468Y1503835D01*
X2255939Y1504418D01*
X2249171D01*
G01X2267326Y1512585D02*
Y1495085D01*
X2276060D01*
G01X2293560D02*
X2284826D01*
Y1512585D01*
X2293560D01*
G01X2290066Y1504127D02*
X2284826D01*
G01X2306693Y1494502D02*
X2306256Y1494793D01*
Y1495377D01*
X2306693Y1495668D01*
X2307130Y1495377D01*
Y1494793D01*
X2306693Y1494502D01*
G01Y1502376D02*
X2306256Y1502668D01*
Y1503252D01*
X2306693Y1503543D01*
X2307130Y1503252D01*
Y1502668D01*
X2306693Y1502376D01*
G01X2337326Y1512585D02*
Y1495085D01*
X2346060D01*
G01X2359193D02*
Y1512585D01*
X2356573Y1509085D01*
G01Y1495085D02*
X2361813D01*
G01X2008773Y1477935D02*
X2014013D01*
G01X2011393D02*
Y1460435D01*
G01X2008773D02*
X2014013D01*
G01X2023216D02*
Y1477935D01*
X2028893Y1463352D01*
X2034570Y1477935D01*
Y1460435D01*
G01X2042026D02*
Y1477935D01*
X2047266D01*
X2049013Y1477060D01*
X2050323Y1475018D01*
X2050760Y1472685D01*
X2050323Y1470352D01*
X2049231Y1468602D01*
X2047266Y1467726D01*
X2042026D01*
G01X2062801Y1454602D02*
X2060618Y1457518D01*
X2059526Y1460435D01*
Y1472101D01*
X2060618Y1475018D01*
X2062801Y1477935D01*
G01X2081393Y1460435D02*
X2079646Y1460727D01*
X2078118Y1461893D01*
X2076808Y1463643D01*
X2075934Y1465685D01*
X2075498Y1468018D01*
Y1470352D01*
X2075934Y1472685D01*
X2076808Y1474727D01*
X2078118Y1476476D01*
X2079646Y1477643D01*
X2081393Y1477935D01*
X2083139Y1477643D01*
X2084668Y1476476D01*
X2085978Y1474727D01*
X2086852Y1472685D01*
X2087288Y1470352D01*
Y1468018D01*
X2086852Y1465685D01*
X2085978Y1463643D01*
X2084668Y1461893D01*
X2083139Y1460727D01*
X2081393Y1460435D01*
G01X2095181D02*
Y1477935D01*
G01Y1469477D02*
X2096273Y1470935D01*
X2097365Y1471810D01*
X2099111Y1472101D01*
X2100421Y1471810D01*
X2101950Y1470643D01*
X2102605Y1468893D01*
Y1460435D01*
G01X2109843D02*
Y1472101D01*
G01Y1468893D02*
X2110498Y1470352D01*
X2111590Y1471518D01*
X2113118Y1472101D01*
X2114646Y1471518D01*
X2115738Y1470352D01*
X2116393Y1468893D01*
Y1460435D01*
G01Y1468893D02*
X2117048Y1470352D01*
X2118139Y1471518D01*
X2119668Y1472101D01*
X2121196Y1471518D01*
X2122288Y1470352D01*
X2122943Y1468602D01*
Y1460435D01*
G01X2134985Y1454602D02*
X2137168Y1457518D01*
X2138260Y1460435D01*
Y1472101D01*
X2137168Y1475018D01*
X2134985Y1477935D01*
G01X2041590Y1428409D02*
X2042899Y1426951D01*
X2044428Y1426077D01*
X2046393Y1425785D01*
X2048358Y1426368D01*
X2049886Y1427535D01*
X2050978Y1429576D01*
X2051196Y1431910D01*
X2050760Y1434243D01*
X2049668Y1435702D01*
X2048139Y1436868D01*
X2046611Y1437160D01*
X2045083Y1436868D01*
X2043118Y1435702D01*
X2043773Y1443285D01*
X2049668D01*
G01X2063893D02*
X2062146Y1442702D01*
X2060836Y1441243D01*
X2059963Y1439494D01*
X2059308Y1437160D01*
X2059090Y1434535D01*
X2059308Y1431910D01*
X2059963Y1429576D01*
X2060836Y1427826D01*
X2062146Y1426368D01*
X2063893Y1425785D01*
X2065639Y1426368D01*
X2066950Y1427826D01*
X2067823Y1429576D01*
X2068478Y1431910D01*
X2068696Y1434535D01*
X2068478Y1437160D01*
X2067823Y1439494D01*
X2066950Y1441243D01*
X2065639Y1442702D01*
X2063893Y1443285D01*
G01X2081393Y1425202D02*
X2080956Y1425493D01*
Y1426077D01*
X2081393Y1426368D01*
X2081830Y1426077D01*
Y1425493D01*
X2081393Y1425202D01*
G01X2098893Y1443285D02*
X2097146Y1442702D01*
X2095836Y1441243D01*
X2094963Y1439494D01*
X2094308Y1437160D01*
X2094090Y1434535D01*
X2094308Y1431910D01*
X2094963Y1429576D01*
X2095836Y1427826D01*
X2097146Y1426368D01*
X2098893Y1425785D01*
X2100639Y1426368D01*
X2101950Y1427826D01*
X2102823Y1429576D01*
X2103478Y1431910D01*
X2103696Y1434535D01*
X2103478Y1437160D01*
X2102823Y1439494D01*
X2101950Y1441243D01*
X2100639Y1442702D01*
X2098893Y1443285D01*
G01X2179843Y1477935D02*
X2182899Y1460435D01*
X2186393Y1477935D01*
X2189886Y1460435D01*
X2192943Y1477935D01*
G01X2201273D02*
X2206513D01*
G01X2203893D02*
Y1460435D01*
G01X2201273D02*
X2206513D01*
G01X2216590D02*
Y1477935D01*
X2220956D01*
X2222703Y1477060D01*
X2224013Y1475893D01*
X2225105Y1474144D01*
X2225978Y1472101D01*
X2226196Y1469185D01*
X2225978Y1466268D01*
X2225105Y1464226D01*
X2224013Y1462476D01*
X2222703Y1461310D01*
X2220956Y1460435D01*
X2216590D01*
G01X2238893Y1477935D02*
Y1460435D01*
G01X2233871Y1477935D02*
X2243915D01*
G01X2251808Y1460435D02*
Y1477935D01*
G01X2260978D02*
Y1460435D01*
G01Y1469185D02*
X2251808D01*
G01X2272801Y1454602D02*
X2270618Y1457518D01*
X2269526Y1460435D01*
Y1472101D01*
X2270618Y1475018D01*
X2272801Y1477935D01*
G01X2284843Y1460435D02*
Y1472101D01*
G01Y1468893D02*
X2285498Y1470352D01*
X2286590Y1471518D01*
X2288118Y1472101D01*
X2289646Y1471518D01*
X2290738Y1470352D01*
X2291393Y1468893D01*
Y1460435D01*
G01Y1468893D02*
X2292048Y1470352D01*
X2293139Y1471518D01*
X2294668Y1472101D01*
X2296196Y1471518D01*
X2297288Y1470352D01*
X2297943Y1468602D01*
Y1460435D01*
G01X2308893Y1472101D02*
Y1460435D01*
G01Y1476768D02*
X2308456Y1477060D01*
Y1477643D01*
X2308893Y1477935D01*
X2309330Y1477643D01*
Y1477060D01*
X2308893Y1476768D01*
G01X2326393Y1460435D02*
Y1477935D01*
G01X2340618Y1462476D02*
X2341710Y1461310D01*
X2343238Y1460435D01*
X2344548D01*
X2345858Y1461018D01*
X2346731Y1461893D01*
X2347168Y1463059D01*
X2346950Y1464810D01*
X2346076Y1465685D01*
X2342146Y1467435D01*
X2341273Y1469477D01*
X2341710Y1470935D01*
X2342583Y1471810D01*
X2343893Y1472101D01*
X2345203Y1471810D01*
X2346513Y1470935D01*
G01X2362485Y1454602D02*
X2364668Y1457518D01*
X2365760Y1460435D01*
Y1472101D01*
X2364668Y1475018D01*
X2362485Y1477935D01*
G01X2243495Y1433076D02*
X2245023Y1435118D01*
X2246333Y1436285D01*
X2248080Y1436868D01*
X2249608Y1436285D01*
X2250700Y1435118D01*
X2251573Y1433368D01*
X2251791Y1431327D01*
X2251573Y1429576D01*
X2250700Y1427826D01*
X2249389Y1426368D01*
X2247861Y1425785D01*
X2246115Y1426368D01*
X2244586Y1428118D01*
X2243713Y1430743D01*
X2243495Y1433660D01*
X2243931Y1437451D01*
X2244586Y1439494D01*
X2245678Y1441535D01*
X2247206Y1442993D01*
X2248735Y1443285D01*
X2250263Y1442702D01*
X2251355Y1441243D01*
G01X2265143Y1425202D02*
X2264706Y1425493D01*
Y1426077D01*
X2265143Y1426368D01*
X2265580Y1426077D01*
Y1425493D01*
X2265143Y1425202D01*
G01X2282206Y1425785D02*
X2282643Y1429576D01*
X2283298Y1432785D01*
X2284171Y1435702D01*
X2285263Y1438910D01*
X2287010Y1443285D01*
X2278276D01*
G01X2295340Y1428409D02*
X2296649Y1426951D01*
X2298178Y1426077D01*
X2300143Y1425785D01*
X2302108Y1426368D01*
X2303636Y1427535D01*
X2304728Y1429576D01*
X2304946Y1431910D01*
X2304510Y1434243D01*
X2303418Y1435702D01*
X2301889Y1436868D01*
X2300361Y1437160D01*
X2298833Y1436868D01*
X2296868Y1435702D01*
X2297523Y1443285D01*
X2303418D01*
G01X2426808Y1428118D02*
X2428555Y1426660D01*
X2430520Y1425785D01*
X2432266D01*
X2434013Y1426660D01*
X2435323Y1428118D01*
X2435978Y1430160D01*
X2435541Y1432201D01*
X2434450Y1433952D01*
X2432485Y1435118D01*
X2429865Y1435702D01*
X2428336Y1436868D01*
X2427681Y1438910D01*
X2428118Y1440952D01*
X2429210Y1442410D01*
X2430738Y1443285D01*
X2432266D01*
X2433795Y1442702D01*
X2435105Y1441243D01*
G01X2453260Y1425785D02*
X2444526D01*
Y1443285D01*
X2453260D01*
G01X2449766Y1434827D02*
X2444526D01*
G01X2413893Y1477935D02*
Y1460435D01*
G01X2408871Y1477935D02*
X2418915D01*
G01X2431393Y1460435D02*
Y1468310D01*
X2427026Y1477935D01*
G01X2435760D02*
X2431393Y1468310D01*
G01X2444526Y1460435D02*
Y1477935D01*
X2449766D01*
X2451513Y1477060D01*
X2452823Y1475018D01*
X2453260Y1472685D01*
X2452823Y1470352D01*
X2451731Y1468602D01*
X2449766Y1467726D01*
X2444526D01*
G01X2470760Y1460435D02*
X2462026D01*
Y1477935D01*
X2470760D01*
G01X2467266Y1469477D02*
X2462026D01*
G01X2514526Y1460435D02*
Y1477935D01*
X2519985D01*
X2521731Y1477060D01*
X2522823Y1475893D01*
X2523260Y1473560D01*
X2522823Y1471226D01*
X2521513Y1469768D01*
X2519985Y1468893D01*
X2514526D01*
G01X2519985D02*
X2523260Y1460435D01*
G01X2533118Y1468310D02*
X2540105D01*
X2539450Y1470352D01*
X2538358Y1471518D01*
X2536830Y1472101D01*
X2535301Y1471810D01*
X2533991Y1470935D01*
X2533118Y1468893D01*
X2532681Y1467143D01*
Y1465393D01*
X2533118Y1463643D01*
X2534210Y1461893D01*
X2535520Y1460727D01*
X2537048Y1460435D01*
X2538576Y1461018D01*
X2540105Y1462768D01*
G01X2552583Y1460435D02*
Y1475310D01*
X2553020Y1476768D01*
X2553893Y1477643D01*
X2555203Y1477935D01*
X2556513Y1477352D01*
X2557168Y1475893D01*
G01X2554548Y1470935D02*
X2550181D01*
G01X2571393Y1459852D02*
X2570956Y1460143D01*
Y1460727D01*
X2571393Y1461018D01*
X2571830Y1460727D01*
Y1460143D01*
X2571393Y1459852D01*
G01X2602026Y1460435D02*
Y1477935D01*
X2607266D01*
X2609013Y1477060D01*
X2610323Y1475018D01*
X2610760Y1472685D01*
X2610323Y1470352D01*
X2609231Y1468602D01*
X2607266Y1467726D01*
X2602026D01*
G01X2623893Y1460435D02*
Y1477935D01*
G01X2645323Y1460435D02*
Y1472101D01*
G01Y1470060D02*
X2644450Y1471226D01*
X2643139Y1471810D01*
X2641611Y1472101D01*
X2640083Y1471518D01*
X2638773Y1470352D01*
X2637899Y1468602D01*
X2637463Y1466268D01*
X2637899Y1463935D01*
X2638773Y1462185D01*
X2640083Y1461018D01*
X2641611Y1460435D01*
X2643139Y1460727D01*
X2644450Y1461601D01*
X2645323Y1462768D01*
G01X2655181Y1460435D02*
Y1472101D01*
G01Y1469185D02*
X2656055Y1470643D01*
X2657365Y1471810D01*
X2659111Y1472101D01*
X2660639Y1471810D01*
X2661950Y1470643D01*
X2662605Y1468602D01*
Y1460435D01*
G01X2673118Y1468310D02*
X2680105D01*
X2679450Y1470352D01*
X2678358Y1471518D01*
X2676830Y1472101D01*
X2675301Y1471810D01*
X2673991Y1470935D01*
X2673118Y1468893D01*
X2672681Y1467143D01*
Y1465393D01*
X2673118Y1463643D01*
X2674210Y1461893D01*
X2675520Y1460727D01*
X2677048Y1460435D01*
X2678576Y1461018D01*
X2680105Y1462768D01*
G01X2584526Y1443285D02*
Y1425785D01*
X2593260D01*
G01X2602245Y1440368D02*
X2603555Y1442118D01*
X2605083Y1442993D01*
X2606830Y1443285D01*
X2609013Y1442702D01*
X2610541Y1441243D01*
X2610978Y1439494D01*
X2610760Y1437743D01*
X2609886Y1436285D01*
X2605520Y1433368D01*
X2603555Y1431327D01*
X2602245Y1428409D01*
X2601808Y1425785D01*
X2610978D01*
G01X2794193Y1437451D02*
Y1425785D01*
G01Y1442118D02*
X2793756Y1442410D01*
Y1442993D01*
X2794193Y1443285D01*
X2794630Y1442993D01*
Y1442410D01*
X2794193Y1442118D01*
G01X2808418Y1427826D02*
X2809510Y1426660D01*
X2811038Y1425785D01*
X2812348D01*
X2813658Y1426368D01*
X2814531Y1427243D01*
X2814968Y1428409D01*
X2814750Y1430160D01*
X2813876Y1431035D01*
X2809946Y1432785D01*
X2809073Y1434827D01*
X2809510Y1436285D01*
X2810383Y1437160D01*
X2811693Y1437451D01*
X2813003Y1437160D01*
X2814313Y1436285D01*
G01X2841671Y1425785D02*
Y1443285D01*
X2851715Y1425785D01*
Y1443285D01*
G01X2864193Y1425785D02*
X2862446Y1426077D01*
X2860918Y1427243D01*
X2859608Y1428993D01*
X2858734Y1431035D01*
X2858298Y1433368D01*
Y1435702D01*
X2858734Y1438035D01*
X2859608Y1440077D01*
X2860918Y1441826D01*
X2862446Y1442993D01*
X2864193Y1443285D01*
X2865939Y1442993D01*
X2867468Y1441826D01*
X2868778Y1440077D01*
X2869652Y1438035D01*
X2870088Y1435702D01*
Y1433368D01*
X2869652Y1431035D01*
X2868778Y1428993D01*
X2867468Y1427243D01*
X2865939Y1426077D01*
X2864193Y1425785D01*
G01X2881693Y1443285D02*
Y1425785D01*
G01X2876671Y1443285D02*
X2886715D01*
G01X2912981Y1437451D02*
Y1429285D01*
X2913855Y1427243D01*
X2915165Y1426077D01*
X2916693Y1425785D01*
X2918221Y1426077D01*
X2919531Y1427243D01*
X2920405Y1429285D01*
G01Y1425785D02*
Y1437451D01*
G01X2930918Y1427826D02*
X2932010Y1426660D01*
X2933538Y1425785D01*
X2934848D01*
X2936158Y1426368D01*
X2937031Y1427243D01*
X2937468Y1428409D01*
X2937250Y1430160D01*
X2936376Y1431035D01*
X2932446Y1432785D01*
X2931573Y1434827D01*
X2932010Y1436285D01*
X2932883Y1437160D01*
X2934193Y1437451D01*
X2935503Y1437160D01*
X2936813Y1436285D01*
G01X2948418Y1433660D02*
X2955405D01*
X2954750Y1435702D01*
X2953658Y1436868D01*
X2952130Y1437451D01*
X2950601Y1437160D01*
X2949291Y1436285D01*
X2948418Y1434243D01*
X2947981Y1432493D01*
Y1430743D01*
X2948418Y1428993D01*
X2949510Y1427243D01*
X2950820Y1426077D01*
X2952348Y1425785D01*
X2953876Y1426368D01*
X2955405Y1428118D01*
G01X2973123Y1443285D02*
Y1425785D01*
G01Y1428409D02*
X2972250Y1426951D01*
X2970939Y1426077D01*
X2969411Y1425785D01*
X2967665Y1426368D01*
X2966355Y1427826D01*
X2965481Y1429576D01*
X2965263Y1431618D01*
X2965481Y1433660D01*
X2966355Y1435410D01*
X2967665Y1436868D01*
X2969411Y1437451D01*
X2970939Y1437160D01*
X2972031Y1436576D01*
X2973123Y1435410D01*
G01X2719390Y1459852D02*
X2728996Y1472685D01*
G01X2724193Y1475018D02*
Y1457518D01*
G01X2728996Y1459852D02*
X2719390Y1472685D01*
G01X2717643Y1466268D02*
X2730743D01*
G01X2756355D02*
X2762031D01*
G01X2789390Y1460435D02*
Y1477935D01*
X2793756D01*
X2795503Y1477060D01*
X2796813Y1475893D01*
X2797905Y1474144D01*
X2798778Y1472101D01*
X2798996Y1469185D01*
X2798778Y1466268D01*
X2797905Y1464226D01*
X2796813Y1462476D01*
X2795503Y1461310D01*
X2793756Y1460435D01*
X2789390D01*
G01X2808418Y1468310D02*
X2815405D01*
X2814750Y1470352D01*
X2813658Y1471518D01*
X2812130Y1472101D01*
X2810601Y1471810D01*
X2809291Y1470935D01*
X2808418Y1468893D01*
X2807981Y1467143D01*
Y1465393D01*
X2808418Y1463643D01*
X2809510Y1461893D01*
X2810820Y1460727D01*
X2812348Y1460435D01*
X2813876Y1461018D01*
X2815405Y1462768D01*
G01X2825481Y1460435D02*
Y1472101D01*
G01Y1469185D02*
X2826355Y1470643D01*
X2827665Y1471810D01*
X2829411Y1472101D01*
X2830939Y1471810D01*
X2832250Y1470643D01*
X2832905Y1468602D01*
Y1460435D01*
G01X2846693D02*
X2845383Y1460727D01*
X2844073Y1461893D01*
X2843199Y1463935D01*
X2842763Y1466268D01*
X2843199Y1468602D01*
X2844073Y1470643D01*
X2845383Y1471810D01*
X2846693Y1472101D01*
X2848003Y1471810D01*
X2849313Y1470643D01*
X2850186Y1468602D01*
X2850405Y1466268D01*
X2850186Y1463935D01*
X2849313Y1461893D01*
X2848003Y1460727D01*
X2846693Y1460435D01*
G01X2864193Y1477935D02*
Y1460435D01*
G01X2861136Y1472101D02*
X2867250D01*
G01X2878418Y1468310D02*
X2885405D01*
X2884750Y1470352D01*
X2883658Y1471518D01*
X2882130Y1472101D01*
X2880601Y1471810D01*
X2879291Y1470935D01*
X2878418Y1468893D01*
X2877981Y1467143D01*
Y1465393D01*
X2878418Y1463643D01*
X2879510Y1461893D01*
X2880820Y1460727D01*
X2882348Y1460435D01*
X2883876Y1461018D01*
X2885405Y1462768D01*
G01X2895918Y1462476D02*
X2897010Y1461310D01*
X2898538Y1460435D01*
X2899848D01*
X2901158Y1461018D01*
X2902031Y1461893D01*
X2902468Y1463059D01*
X2902250Y1464810D01*
X2901376Y1465685D01*
X2897446Y1467435D01*
X2896573Y1469477D01*
X2897010Y1470935D01*
X2897883Y1471810D01*
X2899193Y1472101D01*
X2900503Y1471810D01*
X2901813Y1470935D01*
G01X2934193Y1477935D02*
Y1460435D01*
G01X2931136Y1472101D02*
X2937250D01*
G01X2947981Y1460435D02*
Y1477935D01*
G01Y1469477D02*
X2949073Y1470935D01*
X2950165Y1471810D01*
X2951911Y1472101D01*
X2953221Y1471810D01*
X2954750Y1470643D01*
X2955405Y1468893D01*
Y1460435D01*
G01X2973123D02*
Y1472101D01*
G01Y1470060D02*
X2972250Y1471226D01*
X2970939Y1471810D01*
X2969411Y1472101D01*
X2967883Y1471518D01*
X2966573Y1470352D01*
X2965699Y1468602D01*
X2965263Y1466268D01*
X2965699Y1463935D01*
X2966573Y1462185D01*
X2967883Y1461018D01*
X2969411Y1460435D01*
X2970939Y1460727D01*
X2972250Y1461601D01*
X2973123Y1462768D01*
G01X2986693Y1477935D02*
Y1460435D01*
G01X2983636Y1472101D02*
X2989750D01*
G01X3021693Y1477935D02*
Y1460435D01*
G01X3018636Y1472101D02*
X3024750D01*
G01X3035481Y1460435D02*
Y1477935D01*
G01Y1469477D02*
X3036573Y1470935D01*
X3037665Y1471810D01*
X3039411Y1472101D01*
X3040721Y1471810D01*
X3042250Y1470643D01*
X3042905Y1468893D01*
Y1460435D01*
G01X3056693Y1472101D02*
Y1460435D01*
G01Y1476768D02*
X3056256Y1477060D01*
Y1477643D01*
X3056693Y1477935D01*
X3057130Y1477643D01*
Y1477060D01*
X3056693Y1476768D01*
G01X3070918Y1462476D02*
X3072010Y1461310D01*
X3073538Y1460435D01*
X3074848D01*
X3076158Y1461018D01*
X3077031Y1461893D01*
X3077468Y1463059D01*
X3077250Y1464810D01*
X3076376Y1465685D01*
X3072446Y1467435D01*
X3071573Y1469477D01*
X3072010Y1470935D01*
X3072883Y1471810D01*
X3074193Y1472101D01*
X3075503Y1471810D01*
X3076813Y1470935D01*
G01X3106573Y1477935D02*
X3111813D01*
G01X3109193D02*
Y1460435D01*
G01X3106573D02*
X3111813D01*
G01X3120143D02*
Y1472101D01*
G01Y1468893D02*
X3120798Y1470352D01*
X3121890Y1471518D01*
X3123418Y1472101D01*
X3124946Y1471518D01*
X3126038Y1470352D01*
X3126693Y1468893D01*
Y1460435D01*
G01Y1468893D02*
X3127348Y1470352D01*
X3128439Y1471518D01*
X3129968Y1472101D01*
X3131496Y1471518D01*
X3132588Y1470352D01*
X3133243Y1468602D01*
Y1460435D01*
G01X3140263Y1454602D02*
Y1472101D01*
G01Y1469477D02*
X3141355Y1470935D01*
X3142446Y1471810D01*
X3144193Y1472101D01*
X3145721Y1471810D01*
X3147250Y1470352D01*
X3147905Y1468310D01*
X3148123Y1466268D01*
X3147905Y1464226D01*
X3147250Y1462185D01*
X3145939Y1461018D01*
X3144193Y1460435D01*
X3142665Y1460727D01*
X3141136Y1461601D01*
X3140263Y1462768D01*
G01X3158418Y1468310D02*
X3165405D01*
X3164750Y1470352D01*
X3163658Y1471518D01*
X3162130Y1472101D01*
X3160601Y1471810D01*
X3159291Y1470935D01*
X3158418Y1468893D01*
X3157981Y1467143D01*
Y1465393D01*
X3158418Y1463643D01*
X3159510Y1461893D01*
X3160820Y1460727D01*
X3162348Y1460435D01*
X3163876Y1461018D01*
X3165405Y1462768D01*
G01X3183123Y1477935D02*
Y1460435D01*
G01Y1463059D02*
X3182250Y1461601D01*
X3180939Y1460727D01*
X3179411Y1460435D01*
X3177665Y1461018D01*
X3176355Y1462476D01*
X3175481Y1464226D01*
X3175263Y1466268D01*
X3175481Y1468310D01*
X3176355Y1470060D01*
X3177665Y1471518D01*
X3179411Y1472101D01*
X3180939Y1471810D01*
X3182031Y1471226D01*
X3183123Y1470060D01*
G01X3200623Y1460435D02*
Y1472101D01*
G01Y1470060D02*
X3199750Y1471226D01*
X3198439Y1471810D01*
X3196911Y1472101D01*
X3195383Y1471518D01*
X3194073Y1470352D01*
X3193199Y1468602D01*
X3192763Y1466268D01*
X3193199Y1463935D01*
X3194073Y1462185D01*
X3195383Y1461018D01*
X3196911Y1460435D01*
X3198439Y1460727D01*
X3199750Y1461601D01*
X3200623Y1462768D01*
G01X3210481Y1460435D02*
Y1472101D01*
G01Y1469185D02*
X3211355Y1470643D01*
X3212665Y1471810D01*
X3214411Y1472101D01*
X3215939Y1471810D01*
X3217250Y1470643D01*
X3217905Y1468602D01*
Y1460435D01*
G01X3235186Y1470643D02*
X3233658Y1471810D01*
X3232348Y1472101D01*
X3230601Y1471518D01*
X3229291Y1470352D01*
X3228418Y1468310D01*
X3228199Y1466268D01*
X3228418Y1464226D01*
X3229291Y1462476D01*
X3230601Y1461018D01*
X3232348Y1460435D01*
X3233876Y1461018D01*
X3235186Y1462185D01*
G01X3245918Y1468310D02*
X3252905D01*
X3252250Y1470352D01*
X3251158Y1471518D01*
X3249630Y1472101D01*
X3248101Y1471810D01*
X3246791Y1470935D01*
X3245918Y1468893D01*
X3245481Y1467143D01*
Y1465393D01*
X3245918Y1463643D01*
X3247010Y1461893D01*
X3248320Y1460727D01*
X3249848Y1460435D01*
X3251376Y1461018D01*
X3252905Y1462768D01*
G01X0Y3937D02*
G03X3937Y0I3937J0D01*
G01X0Y3937D02*
G03X3937Y0I3937J0D01*
G01D02*
X779528D01*
G01X3937D02*
X779528D01*
G01X0Y1456693D02*
Y3937D01*
G01Y1456693D02*
Y3937D01*
G01X7874Y1460630D02*
X3937D01*
G01D02*
X7874D01*
G01X3937D02*
G03X0Y1456693I0J-3937D01*
G01X3937Y1460630D02*
G03X0Y1456693I0J-3937D01*
G01X101378Y1519685D02*
G03X97441Y1515748I0J-3937D01*
G01X101378Y1519685D02*
G03X97441Y1515748I0J-3937D01*
G01D02*
Y1509055D01*
G01Y1515748D02*
Y1509055D01*
G01X93504Y1505118D02*
X67913D01*
G01X93504D02*
G03X97441Y1509055I0J3937D01*
G01X93504Y1505118D02*
G03X97441Y1509055I0J3937D01*
G01X67913Y1505118D02*
X93504D01*
G01X63976Y1515748D02*
G03X60039Y1519685I-3937J0D01*
G01X63976Y1515748D02*
G03X60039Y1519685I-3937J0D01*
G01X63976Y1509055D02*
Y1515748D01*
G01Y1509055D02*
G03X67913Y1505118I3937J0D01*
G01X63976Y1509055D02*
G03X67913Y1505118I3937J0D01*
G01X63976Y1515748D02*
Y1509055D01*
G01X7874Y1460630D02*
G03X11811Y1464567I0J3937D01*
G01X7874Y1460630D02*
G03X11811Y1464567I0J3937D01*
G01X15748Y1519685D02*
G03X11811Y1515748I0J-3937D01*
G01X15748Y1519685D02*
G03X11811Y1515748I0J-3937D01*
G01D02*
Y1464567D01*
G01Y1515748D02*
Y1464567D01*
G01X60039Y1519685D02*
X15748D01*
G01X60039D02*
X15748D01*
G01X141181Y277843D02*
G03X148106Y264712I37662J11471D01*
G01X141181Y277843D02*
G03X148106Y264712I37662J11471D01*
G01X141181Y277843D02*
G03X121220I-9980J-3040D01*
G01X114295Y264712D02*
G03X121220Y277843I-30737J24602D01*
G01X141181D02*
G03X121220I-9980J-3040D01*
G01X114295Y264712D02*
G03X121220Y277843I-30737J24601D01*
G01X114295Y264712D02*
G03X148106I16905J-13531D01*
G01X114295D02*
G03X148106I16905J-13531D01*
G01X141181Y730599D02*
G03X148106Y717468I37662J11471D01*
G01X141181Y730599D02*
G03X148106Y717468I37662J11471D01*
G01X141181Y730599D02*
G03X121220I-9980J-3040D01*
G01X114295Y717468D02*
G03X121220Y730599I-30737J24601D01*
G01X141181D02*
G03X121220I-9980J-3040D01*
G01X114295Y717468D02*
G03X121220Y730599I-30737J24601D01*
G01X114295Y717468D02*
G03X148106I16905J-13531D01*
G01X114295D02*
G03X148106I16905J-13531D01*
G01X114295Y1170224D02*
G03X148106I16905J-13531D01*
G01X114295D02*
G03X148106I16905J-13531D01*
G01X141181Y1183355D02*
G03X148106Y1170224I37662J11471D01*
G01X141181Y1183355D02*
G03X148106Y1170224I37662J11471D01*
G01X141181Y1183355D02*
G03X121220I-9980J-3040D01*
G01X141181D02*
G03X121220I-9980J-3040D01*
G01X114295Y1170224D02*
G03X121220Y1183355I-30737J24602D01*
G01X114295Y1170224D02*
G03X121220Y1183355I-30737J24601D01*
G01X280709Y1519685D02*
X101378D01*
G01X280709D02*
X101378D01*
G01X284646Y1515748D02*
G03X280709Y1519685I-3937J0D01*
G01X284646Y1515748D02*
G03X280709Y1519685I-3937J0D01*
G01X284646Y1500000D02*
Y1515748D01*
G01Y1500000D02*
G03X288583Y1496063I3937J0D01*
G01X493307D02*
X288583D01*
G01X284646Y1500000D02*
G03X288583Y1496063I3937J0D01*
G01X493307D02*
X288583D01*
G01X284646Y1515748D02*
Y1500000D01*
G01X389213Y277843D02*
G03X369252I-9981J-3040D01*
G01X389213D02*
G03X369252I-9981J-3040D01*
G01X362327Y264712D02*
G03X369252Y277843I-30737J24602D01*
G01X362327Y264712D02*
G03X369252Y277843I-30737J24602D01*
G01X362327Y264712D02*
G03X396138I16905J-13531D01*
G01X362327D02*
G03X396138I16905J-13531D01*
G01X389213Y730599D02*
G03X369252I-9981J-3040D01*
G01X389213D02*
G03X369252I-9981J-3040D01*
G01X362327Y717468D02*
G03X369252Y730599I-30737J24602D01*
G01X362327Y717468D02*
G03X369252Y730599I-30737J24602D01*
G01X362327Y717468D02*
G03X396138I16905J-13531D01*
G01X362327D02*
G03X396138I16905J-13531D01*
G01X362327Y1170224D02*
G03X396138I16905J-13531D01*
G01X362327D02*
G03X396138I16905J-13531D01*
G01X389213Y1183355D02*
G03X369252I-9981J-3040D01*
G01X389213D02*
G03X369252I-9981J-3040D01*
G01X362327Y1170224D02*
G03X369252Y1183355I-30737J24602D01*
G01X362327Y1170224D02*
G03X369252Y1183355I-30737J24602D01*
G01X322441Y1503937D02*
G03Y1496063I0J-3937D01*
G01X459449Y1503937D02*
X322441D01*
G01X459449D02*
X322441D01*
G01D02*
G03Y1496063I0J-3937D01*
G01X296457Y1519685D02*
G03X292520Y1515748I0J-3937D01*
G01X296457Y1519685D02*
X485433D01*
G01X296457D02*
G03X292520Y1515748I0J-3937D01*
G01X296457Y1519685D02*
X485433D01*
G01X304331Y1503937D02*
X292520D01*
G01Y1515748D02*
Y1503937D01*
G01X304331D02*
X292520D01*
G01Y1515748D02*
Y1503937D01*
G01X304331Y1496063D02*
G03Y1503937I0J3937D01*
G01Y1496063D02*
G03Y1503937I0J3937D01*
G01X389213Y277843D02*
G03X396138Y264712I37662J11471D01*
G01X389213Y277843D02*
G03X396138Y264712I37662J11470D01*
G01X389213Y730599D02*
G03X396138Y717468I37662J11471D01*
G01X389213Y730599D02*
G03X396138Y717468I37662J11470D01*
G01X389213Y1183355D02*
G03X396138Y1170224I37662J11471D01*
G01X389213Y1183355D02*
G03X396138Y1170224I37662J11470D01*
G01X477559Y1503937D02*
G03Y1496063I0J-3937D01*
G01X459449D02*
G03Y1503937I0J3937D01*
G01X489370D02*
X477559D01*
G01D02*
G03Y1496063I0J-3937D01*
G01X459449D02*
G03Y1503937I0J3937D01*
G01X489370D02*
X477559D01*
G01X489370Y1515748D02*
G03X485433Y1519685I-3937J0D01*
G01X489370Y1515748D02*
G03X485433Y1519685I-3937J0D01*
G01X501181D02*
G03X497244Y1515748I0J-3937D01*
G01X680512Y1519685D02*
X501181D01*
G01D02*
G03X497244Y1515748I0J-3937D01*
G01X680512Y1519685D02*
X501181D01*
G01X489370Y1515748D02*
Y1503937D01*
G01X493307Y1496063D02*
G03X497244Y1500000I0J3937D01*
G01Y1515748D02*
Y1500000D01*
G01X489370Y1515748D02*
Y1503937D01*
G01X493307Y1496063D02*
G03X497244Y1500000I0J3937D01*
G01Y1515748D02*
Y1500000D01*
G01X637244Y277843D02*
G03X644169Y264712I37662J11471D01*
G01X637244Y277843D02*
G03X644169Y264712I37662J11471D01*
G01X637244Y277843D02*
G03X617283I-9980J-3040D01*
G01X610358Y264712D02*
G03X617283Y277843I-30737J24602D01*
G01X637244D02*
G03X617283I-9980J-3040D01*
G01X610358Y264712D02*
G03X617283Y277843I-30737J24601D01*
G01X610358Y264712D02*
G03X644169I16906J-13531D01*
G01X610358D02*
G03X644169I16906J-13531D01*
G01X637244Y730599D02*
G03X644169Y717468I37662J11471D01*
G01X637244Y730599D02*
G03X644169Y717468I37662J11471D01*
G01X637244Y730599D02*
G03X617283I-9980J-3040D01*
G01X610358Y717468D02*
G03X617283Y730599I-30737J24601D01*
G01X637244D02*
G03X617283I-9980J-3040D01*
G01X610358Y717468D02*
G03X617283Y730599I-30737J24601D01*
G01X610358Y717468D02*
G03X644169I16906J-13531D01*
G01X610358D02*
G03X644169I16906J-13531D01*
G01X610358Y1170224D02*
G03X644169I16906J-13531D01*
G01X610358D02*
G03X644169I16906J-13531D01*
G01X637244Y1183355D02*
G03X644169Y1170224I37662J11471D01*
G01X637244Y1183355D02*
G03X644169Y1170224I37662J11471D01*
G01X637244Y1183355D02*
G03X617283I-9980J-3040D01*
G01X637244D02*
G03X617283I-9980J-3040D01*
G01X610358Y1170224D02*
G03X617283Y1183355I-30737J24602D01*
G01X610358Y1170224D02*
G03X617283Y1183355I-30737J24601D01*
G01X730339Y383610D02*
G03X764149I16905J-13531D01*
G01X730339Y383609D02*
G03X764150I16905J-13530D01*
G01X757225Y396741D02*
G03X764149Y383610I37663J11469D01*
G01X757224Y396741D02*
G03X764150Y383609I37662J11471D01*
G01X757225Y396741D02*
G03X737264I-9981J-3040D01*
G01X730339Y383610D02*
G03X737264Y396741I-30737J24602D01*
G01X757224D02*
G03X737264I-9980J-3041D01*
G01X730339Y383609D02*
G03X737264Y396741I-30738J24601D01*
G01X757225Y829811D02*
G03X764149Y816680I37663J11469D01*
G01X757224Y829811D02*
G03X764150Y816680I37662J11473D01*
G01X757225Y829811D02*
G03X737264I-9981J-3039D01*
G01X757224D02*
G03X737264I-9980J-3040D01*
G01X730339Y816680D02*
G03X737264Y829811I-30737J24602D01*
G01X730339Y816680D02*
G03X737264Y829811I-30737J24602D01*
G01X730339Y816680D02*
G03X764149I16905J-13531D01*
G01X730339D02*
G03X764150I16905J-13531D01*
G01X721850Y1519685D02*
G03X717913Y1515748I0J-3937D01*
G01X775591Y1519685D02*
X721850D01*
G01D02*
G03X717913Y1515748I0J-3937D01*
G01X775591Y1519685D02*
X721850D01*
G01X713976Y1505118D02*
G03X717913Y1509055I0J3937D01*
G01Y1515748D02*
Y1509055D01*
G01X713976Y1505118D02*
G03X717913Y1509055I0J3937D01*
G01Y1515748D02*
Y1509055D01*
G01X684449Y1515748D02*
G03X680512Y1519685I-3937J0D01*
G01X684449Y1515748D02*
G03X680512Y1519685I-3937J0D01*
G01X684449Y1509055D02*
Y1515748D01*
G01Y1509055D02*
G03X688386Y1505118I3937J0D01*
G01X713976D02*
X688386D01*
G01X684449Y1509055D02*
G03X688386Y1505118I3937J0D01*
G01D02*
X713976D01*
G01X684449Y1515748D02*
Y1509055D01*
G01X791339Y3937D02*
G03X795276Y0I3937J0D01*
G01D02*
X892317D01*
G01X791339Y3937D02*
Y23622D01*
G01Y3937D02*
G03X795276Y0I3937J0D01*
G01X791339Y3937D02*
Y23622D01*
G01X795276Y0D02*
X892317D01*
G01X783465Y54331D02*
G03X791339I3937J0D01*
G01X783465D02*
G03X791339I3937J0D01*
G01Y23622D02*
G03X783465I-3937J0D01*
G01X791339D02*
G03X783465I-3937J0D01*
G01X779528Y0D02*
G03X783465Y3937I0J3937D01*
G01X779528Y0D02*
G03X783465Y3937I0J3937D01*
G01X791339Y54331D02*
Y181890D01*
G01Y54331D02*
Y181890D01*
G01X783465Y3937D02*
Y185827D01*
G01Y3937D02*
Y185827D01*
G01X811024Y181890D02*
G03X822835Y193701I0J11811D01*
G01X791339Y181890D02*
X811024D01*
G01D02*
G03X822835Y193701I0J11811D01*
G01X791339Y181890D02*
X811024D01*
G01X787402Y189764D02*
G03X783465Y185827I0J-3937D01*
G01X787402Y189764D02*
G03X783465Y185827I0J-3937D01*
G01X811024Y189764D02*
G03X814961Y193701I0J3937D01*
G01X787402Y189764D02*
X811024D01*
G01D02*
G03X814961Y193701I0J3937D01*
G01X787402Y189764D02*
X811024D01*
G01X822835Y193701D02*
Y240157D01*
G01Y193701D02*
Y240157D01*
G01X814961Y193701D02*
Y244094D01*
G01Y193701D02*
Y244094D01*
G01X818898Y248031D02*
G03X814961Y244094I0J-3937D01*
G01X818898Y248031D02*
G03X814961Y244094I0J-3937D01*
G01X928098Y240157D02*
X822835D01*
G01X928098D02*
X822835D01*
G01X818898Y248031D02*
X1055118D01*
G01D02*
X818898D01*
G01X954331Y1503937D02*
X817323D01*
G01X954331D02*
X817323D01*
G01X791339Y1519685D02*
G03X787402Y1515748I0J-3937D01*
G01X791339Y1519685D02*
X980315D01*
G01X791339D02*
G03X787402Y1515748I0J-3937D01*
G01X791339Y1519685D02*
X980315D01*
G01X817323Y1503937D02*
G03Y1496063I0J-3937D01*
G01X799213D02*
G03Y1503937I0J3937D01*
G01D02*
X787402D01*
G01Y1515748D02*
Y1503937D01*
G01X799213D02*
X787402D01*
G01X817323D02*
G03Y1496063I0J-3937D01*
G01X799213D02*
G03Y1503937I0J3937D01*
G01X787402Y1515748D02*
Y1503937D01*
G01X779528Y1515748D02*
G03X775591Y1519685I-3937J0D01*
G01X779528Y1515748D02*
G03X775591Y1519685I-3937J0D01*
G01X779528Y1500000D02*
Y1515748D01*
G01Y1500000D02*
G03X783465Y1496063I3937J0D01*
G01X988189D02*
X783465D01*
G01X779528Y1500000D02*
G03X783465Y1496063I3937J0D01*
G01X988189D02*
X783465D01*
G01X779528Y1515748D02*
Y1500000D01*
G01X900191Y0D02*
G03X892317I-3937J0D01*
G01X896254D02*
Y-394D01*
G01Y0D02*
Y394D01*
G01X895762Y0D02*
X896746D01*
G01X900191D02*
G03X892317I-3937J0D01*
G01X900191D02*
X1212598D01*
G01X900191D02*
X1212598D01*
G01X953294Y248031D02*
G03Y240157I1J-3937D01*
G01X1051181D02*
X953294D01*
G01Y248031D02*
G03Y240157I1J-3937D01*
G01X928098D02*
G03Y248031I0J3937D01*
G01Y240157D02*
G03Y248031I0J3937D01*
G01X1051181Y240157D02*
X953294D01*
G01X971398Y718788D02*
G03X951437I-9980J-3040D01*
G01X944512Y705657D02*
G03X951437Y718788I-30737J24602D01*
G01X971398D02*
G03X951437I-9980J-3040D01*
G01X944512Y705657D02*
G03X951437Y718788I-30737J24602D01*
G01X944512Y705657D02*
G03X978323I16905J-13531D01*
G01X944512D02*
G03X978323I16905J-13531D01*
G01X944512Y974161D02*
G03X978323I16905J-13531D01*
G01X944512D02*
G03X978323I16905J-13531D01*
G01X971398Y987292D02*
G03X951437I-9980J-3040D01*
G01X944512Y974161D02*
G03X951437Y987292I-30737J24602D01*
G01X971398D02*
G03X951437I-9980J-3040D01*
G01X944512Y974161D02*
G03X951437Y987292I-30737J24602D01*
G01X954331Y1496063D02*
G03Y1503937I0J3937D01*
G01Y1496063D02*
G03Y1503937I0J3937D01*
G01X1051181Y193701D02*
G03X1062992Y181890I11811J0D01*
G01X1051181Y193701D02*
G03X1062992Y181890I11811J0D01*
G01X1051181Y240157D02*
Y193701D01*
G01Y240157D02*
Y193701D01*
G01X971398Y718788D02*
G03X978323Y705657I37662J11471D01*
G01X971398Y718788D02*
G03X978323Y705657I37662J11470D01*
G01X971398Y987292D02*
G03X978323Y974161I37662J11471D01*
G01X971398Y987292D02*
G03X978323Y974161I37662J11470D01*
G01X1059196Y1519685D02*
X996063D01*
G01X1059196D02*
X996063D01*
G01X984252Y1515748D02*
G03X980315Y1519685I-3937J0D01*
G01X984252Y1515748D02*
G03X980315Y1519685I-3937J0D01*
G01X996063D02*
G03X992126Y1515748I0J-3937D01*
G01X996063Y1519685D02*
G03X992126Y1515748I0J-3937D01*
G01X972441Y1503937D02*
G03Y1496063I0J-3937D01*
G01X984252Y1503937D02*
X972441D01*
G01X984252Y1515748D02*
Y1503937D01*
G01X972441D02*
G03Y1496063I0J-3937D01*
G01X988189D02*
G03X992126Y1500000I0J3937D01*
G01Y1515748D02*
Y1500000D01*
G01X984252Y1515748D02*
Y1503937D01*
G01D02*
X972441D01*
G01X988189Y1496063D02*
G03X992126Y1500000I0J3937D01*
G01Y1515748D02*
Y1500000D01*
G01X1133071Y189764D02*
G03Y181890I0J-3937D01*
G01D02*
X1216535D01*
G01X1133071D02*
X1216535D01*
G01X1133071Y189764D02*
G03Y181890I0J-3937D01*
G01X1102362D02*
G03Y189764I0J3937D01*
G01Y181890D02*
G03Y189764I0J3937D01*
G01X1062992Y181890D02*
X1102362D01*
G01X1062992D02*
X1102362D01*
G01X1059055Y244094D02*
G03X1055118Y248031I-3937J0D01*
G01X1059055Y244094D02*
G03X1055118Y248031I-3937J0D01*
G01X1059055Y244094D02*
Y193701D01*
G01Y244094D02*
Y193701D01*
G01X1062992Y189764D02*
X1220472D01*
G01X1059055Y193701D02*
G03X1062992Y189764I3937J0D01*
G01X1059055Y193701D02*
G03X1062992Y189764I3937J0D01*
G01D02*
X1220472D01*
G01X1085630Y1417323D02*
G03X1089567Y1421260I0J3937D01*
G01X1085630Y1417323D02*
G03X1089567Y1421260I0J3937D01*
G01X1072638D02*
G03X1076575Y1417322I3937J-1D01*
G01X1085630Y1417323D02*
X1076575D01*
G01X1072638Y1421260D02*
G03X1076575Y1417323I3937J0D01*
G01D02*
X1085630D01*
G01X1089567Y1506243D02*
Y1421260D01*
G01Y1506243D02*
Y1421260D01*
G01X1072638D02*
Y1506243D01*
G01D02*
Y1421260D01*
G01X1103009Y1519685D02*
G03X1100225Y1518532I0J-3937D01*
G01X1207283Y1519685D02*
X1103009D01*
G01D02*
G03X1100225Y1518532I0J-3937D01*
G01X1207283Y1519685D02*
X1103009D01*
G01X1090720Y1509027D02*
G03X1089567Y1506243I2784J-2784D01*
G01X1100225Y1518532D02*
X1090720Y1509027D01*
G01D02*
G03X1089567Y1506243I2784J-2784D01*
G01X1100225Y1518532D02*
X1090720Y1509027D01*
G01X1061980Y1518532D02*
G03X1059196Y1519685I-2784J-2784D01*
G01X1061980Y1518532D02*
G03X1059196Y1519685I-2784J-2784D01*
G01X1071485Y1509027D02*
X1061980Y1518532D01*
G01X1072638Y1506243D02*
G03X1071485Y1509027I-3937J0D01*
G01X1072638Y1506243D02*
G03X1071485Y1509027I-3937J0D01*
G01X1061980Y1518532D02*
X1071485Y1509027D01*
G01X1216535Y54331D02*
G03X1224409I3937J0D01*
G01X1216535D02*
Y181890D01*
G01Y54331D02*
Y181890D01*
G01Y54331D02*
G03X1224409I3937J0D01*
G01Y23622D02*
G03X1216535I-3937J0D01*
G01X1224409D02*
G03X1216535I-3937J0D01*
G01X1212598Y0D02*
G03X1216535Y3937I0J3937D01*
G01D02*
Y23622D01*
G01X1212598Y0D02*
G03X1216535Y3937I0J3937D01*
G01X1224409D02*
G03X1228346Y0I3937J0D01*
G01X1224409Y185827D02*
Y3937D01*
G01X1216535D02*
Y23622D01*
G01X1224409Y3937D02*
G03X1228346Y0I3937J0D01*
G01X1224409Y3937D02*
Y185827D01*
G01X1228346Y0D02*
X1930906D01*
G01X1228346D02*
X1930906D01*
G01X1224409Y185827D02*
G03X1220472Y189764I-3937J0D01*
G01X1224409Y185827D02*
G03X1220472Y189764I-3937J0D01*
G01X1164984Y383609D02*
G03X1198795I16906J-13530D01*
G01X1164984D02*
G03X1198795I16906J-13530D01*
G01X1191870Y396741D02*
G03X1198795Y383610I37662J11471D01*
G01X1191870Y396741D02*
G03X1198795Y383609I37663J11469D01*
G01X1191870Y396741D02*
G03X1171909I-9980J-3040D01*
G01X1164984Y383610D02*
G03X1171909Y396741I-30737J24602D01*
G01X1191870D02*
G03X1171909I-9980J-3040D01*
G01X1164984Y383609D02*
G03X1171909Y396741I-30737J24601D01*
G01X1164984Y974161D02*
G03X1198795I16906J-13531D01*
G01X1164984D02*
G03X1198795I16906J-13531D01*
G01X1191870Y987292D02*
G03X1198795Y974161I37662J11471D01*
G01X1191870Y987292D02*
G03X1198795Y974161I37662J11471D01*
G01X1191870Y987292D02*
G03X1171909I-9980J-3040D01*
G01X1164984Y974161D02*
G03X1171909Y987292I-30737J24602D01*
G01X1191870D02*
G03X1171909I-9980J-3040D01*
G01X1164984Y974161D02*
G03X1171909Y987292I-30737J24601D01*
G01X1240748Y1505118D02*
G03X1244685Y1509055I0J3937D01*
G01X1240748Y1505118D02*
G03X1244685Y1509055I0J3937D01*
G01X1211220Y1515748D02*
G03X1207283Y1519685I-3937J0D01*
G01X1211220Y1515748D02*
G03X1207283Y1519685I-3937J0D01*
G01X1211220Y1509055D02*
Y1515748D01*
G01Y1509055D02*
G03X1215157Y1505118I3937J0D01*
G01X1240748D02*
X1215157D01*
G01X1211220Y1509055D02*
G03X1215157Y1505118I3937J0D01*
G01D02*
X1240748D01*
G01X1211220Y1515748D02*
Y1509055D01*
G01X1311851Y277843D02*
G03X1318775Y264712I37663J11469D01*
G01X1311850Y277843D02*
G03X1318776Y264712I37661J11473D01*
G01X1311851Y277843D02*
G03X1291890I-9980J-3040D01*
G01X1284965Y264712D02*
G03X1291890Y277843I-30737J24602D01*
G01X1311850D02*
G03X1291890I-9980J-3040D01*
G01X1284965Y264712D02*
G03X1291890Y277843I-30737J24602D01*
G01X1284965Y264712D02*
G03X1318775I16905J-13531D01*
G01X1284965D02*
G03X1318776I16906J-13531D01*
G01X1311851Y730599D02*
G03X1318775Y717468I37663J11469D01*
G01X1311850Y730599D02*
G03X1318776Y717468I37661J11473D01*
G01X1311851Y730599D02*
G03X1291890I-9980J-3040D01*
G01X1284965Y717468D02*
G03X1291891Y730599I-30736J24604D01*
G01X1311850D02*
G03X1291890I-9980J-3040D01*
G01X1284965Y717468D02*
G03X1291890Y730599I-30737J24602D01*
G01X1284965Y717468D02*
G03X1318775I16905J-13531D01*
G01X1284965D02*
G03X1318776I16906J-13531D01*
G01X1284965Y1170224D02*
G03X1318775I16905J-13531D01*
G01X1284965D02*
G03X1318776I16906J-13531D01*
G01X1311851Y1183355D02*
G03X1318775Y1170224I37663J11469D01*
G01X1311850Y1183355D02*
G03X1318776Y1170224I37661J11473D01*
G01X1311851Y1183355D02*
G03X1291890I-9980J-3040D01*
G01X1311850D02*
G03X1291890I-9980J-3040D01*
G01X1284965Y1170224D02*
G03X1291890Y1183355I-30737J24602D01*
G01X1284965Y1170224D02*
G03X1291890Y1183355I-30737J24602D01*
G01X1248622Y1519685D02*
G03X1244685Y1515748I0J-3937D01*
G01X1427953Y1519685D02*
X1248622D01*
G01D02*
G03X1244685Y1515748I0J-3937D01*
G01X1427953Y1519685D02*
X1248622D01*
G01X1244685Y1515748D02*
Y1509055D01*
G01Y1515748D02*
Y1509055D01*
G01X1431890Y1515748D02*
G03X1427953Y1519685I-3937J0D01*
G01X1431890Y1515748D02*
G03X1427953Y1519685I-3937J0D01*
G01X1431890Y1500000D02*
Y1515748D01*
G01Y1500000D02*
G03X1435827Y1496063I3937J0D01*
G01X1431890Y1500000D02*
G03X1435827Y1496063I3937J0D01*
G01X1431890Y1515748D02*
Y1500000D01*
G01X1532996Y264712D02*
G03X1566807I16906J-13531D01*
G01X1532996D02*
G03X1566807I16906J-13531D01*
G01X1532996Y717468D02*
G03X1566807I16906J-13531D01*
G01X1532996D02*
G03X1566807I16906J-13531D01*
G01X1532996Y1170224D02*
G03X1566807I16906J-13531D01*
G01X1532996D02*
G03X1566807I16906J-13531D01*
G01X1469685Y1503937D02*
G03Y1496063I0J-3937D01*
G01X1451575D02*
G03Y1503937I0J3937D01*
G01X1606693D02*
X1469685D01*
G01X1606693D02*
X1469685D01*
G01D02*
G03Y1496063I0J-3937D01*
G01X1451575D02*
G03Y1503937I0J3937D01*
G01X1443701Y1519685D02*
G03X1439764Y1515748I0J-3937D01*
G01X1443701Y1519685D02*
X1632677D01*
G01X1443701D02*
G03X1439764Y1515748I0J-3937D01*
G01X1443701Y1519685D02*
X1632677D01*
G01X1451575Y1503937D02*
X1439764D01*
G01Y1515748D02*
Y1503937D01*
G01X1451575D02*
X1439764D01*
G01X1640551Y1496063D02*
X1435827D01*
G01X1439764Y1515748D02*
Y1503937D01*
G01X1640551Y1496063D02*
X1435827D01*
G01X1559882Y277843D02*
G03X1566807Y264712I37662J11471D01*
G01X1559882Y277843D02*
G03X1539921I-9980J-3040D01*
G01X1559882D02*
G03X1566807Y264712I37662J11471D01*
G01X1559882Y277843D02*
G03X1539921I-9980J-3040D01*
G01X1532996Y264712D02*
G03X1539921Y277843I-30737J24602D01*
G01X1532996Y264712D02*
G03X1539921Y277843I-30737J24602D01*
G01X1559882Y730599D02*
G03X1566807Y717468I37662J11471D01*
G01X1559882Y730599D02*
G03X1539921I-9980J-3040D01*
G01X1559882D02*
G03X1566807Y717468I37662J11471D01*
G01X1559882Y730599D02*
G03X1539921I-9980J-3040D01*
G01X1532996Y717468D02*
G03X1539921Y730599I-30737J24601D01*
G01X1532996Y717468D02*
G03X1539921Y730599I-30737J24601D01*
G01X1559882Y1183355D02*
G03X1539921I-9980J-3040D01*
G01X1559882D02*
G03X1539921I-9980J-3040D01*
G01X1559882D02*
G03X1566807Y1170224I37662J11471D01*
G01X1559882Y1183355D02*
G03X1566807Y1170224I37662J11471D01*
G01X1532996D02*
G03X1539921Y1183355I-30737J24602D01*
G01X1532996Y1170224D02*
G03X1539921Y1183355I-30737J24601D01*
G01X1636614Y1503937D02*
X1624803D01*
G01X1636614D02*
X1624803D01*
G01D02*
G03Y1496063I0J-3937D01*
G01X1606693D02*
G03Y1503937I0J3937D01*
G01X1624803D02*
G03Y1496063I0J-3937D01*
G01X1606693D02*
G03Y1503937I0J3937D01*
G01X1636614Y1515748D02*
G03X1632677Y1519685I-3937J0D01*
G01X1636614Y1515748D02*
G03X1632677Y1519685I-3937J0D01*
G01X1648425D02*
G03X1644488Y1515748I0J-3937D01*
G01X1827756Y1519685D02*
X1648425D01*
G01D02*
G03X1644488Y1515748I0J-3937D01*
G01X1827756Y1519685D02*
X1648425D01*
G01X1636614Y1515748D02*
Y1503937D01*
G01X1640551Y1496063D02*
G03X1644488Y1500000I0J3937D01*
G01Y1515748D02*
Y1500000D01*
G01X1636614Y1515748D02*
Y1503937D01*
G01X1640551Y1496063D02*
G03X1644488Y1500000I0J3937D01*
G01Y1515748D02*
Y1500000D01*
G01X1807914Y277843D02*
G03X1814838Y264712I37663J11469D01*
G01X1807913Y277843D02*
G03X1814839Y264712I37661J11473D01*
G01X1807914Y277843D02*
G03X1787953I-9980J-3040D01*
G01X1781028Y264712D02*
G03X1787953Y277843I-30737J24602D01*
G01X1807913D02*
G03X1787953I-9980J-3040D01*
G01X1781028Y264712D02*
G03X1787953Y277843I-30737J24602D01*
G01X1781028Y264712D02*
G03X1814839I16906J-13531D01*
G01X1781028D02*
G03X1814839I16906J-13531D01*
G01X1807914Y730599D02*
G03X1814838Y717468I37663J11469D01*
G01X1807913Y730599D02*
G03X1814839Y717468I37661J11473D01*
G01X1807914Y730599D02*
G03X1787953I-9980J-3040D01*
G01X1781028Y717468D02*
G03X1787954Y730599I-30736J24604D01*
G01X1807913D02*
G03X1787953I-9980J-3040D01*
G01X1781028Y717468D02*
G03X1787953Y730599I-30737J24602D01*
G01X1781028Y717468D02*
G03X1814838I16905J-13531D01*
G01X1781028D02*
G03X1814839I16906J-13531D01*
G01X1781028Y1170224D02*
G03X1814838I16905J-13531D01*
G01X1781028D02*
G03X1814839I16906J-13531D01*
G01X1807914Y1183355D02*
G03X1814838Y1170224I37662J11468D01*
G01X1807913Y1183355D02*
G03X1814839Y1170224I37661J11473D01*
G01X1807914Y1183355D02*
G03X1787953I-9980J-3040D01*
G01X1807913D02*
G03X1787953I-9980J-3040D01*
G01X1781028Y1170224D02*
G03X1787953Y1183355I-30737J24602D01*
G01X1781028Y1170224D02*
G03X1787953Y1183355I-30737J24602D01*
G01X1869094Y1519685D02*
G03X1865157Y1515748I0J-3937D01*
G01X1919094Y1519685D02*
X1869094D01*
G01D02*
G03X1865157Y1515748I0J-3937D01*
G01X1919094Y1519685D02*
X1869094D01*
G01X1865157Y1515748D02*
Y1509055D01*
G01Y1515748D02*
Y1509055D01*
G01X1861220Y1505118D02*
X1835630D01*
G01X1861220D02*
G03X1865157Y1509055I0J3937D01*
G01X1861220Y1505118D02*
G03X1865157Y1509055I0J3937D01*
G01X1835630Y1505118D02*
X1861220D01*
G01X1831693Y1515748D02*
G03X1827756Y1519685I-3937J0D01*
G01X1831693Y1515748D02*
G03X1827756Y1519685I-3937J0D01*
G01X1831693Y1509055D02*
Y1515748D01*
G01Y1509055D02*
G03X1835630Y1505118I3937J0D01*
G01X1831693Y1509055D02*
G03X1835630Y1505118I3937J0D01*
G01X1831693Y1515748D02*
Y1509055D01*
G01X1930906Y0D02*
G03X1934843Y3937I0J3937D01*
G01X1930906Y0D02*
G03X1934843Y3937I0J3937D01*
G01D02*
Y1456693D01*
G01Y3937D02*
Y1456693D01*
G01X1930906Y1460630D02*
X1926969D01*
G01X1934843Y1456693D02*
G03X1930906Y1460630I-3937J0D01*
G01X1934843Y1456693D02*
G03X1930906Y1460630I-3937J0D01*
G01D02*
X1926969D01*
G01X1923031Y1515748D02*
G03X1919094Y1519685I-3937J0D01*
G01X1923031Y1515748D02*
G03X1919094Y1519685I-3937J0D01*
G01X1923031Y1464567D02*
Y1515748D01*
G01Y1464567D02*
G03X1926969Y1460630I3937J0D01*
G01X1923031Y1464567D02*
G03X1926969Y1460630I3937J0D01*
G01X1923031Y1515748D02*
Y1464567D01*
G54D12*
G01X65750Y73250D02*
X60000D01*
G01X66500Y74000D02*
X65750Y73250D01*
G01X60250Y81500D02*
Y96500D01*
G01X60000Y81250D02*
X60250Y81500D01*
G01X60000Y80000D02*
Y81250D01*
G01Y73250D02*
Y80000D01*
G01X71550Y80700D02*
X67750Y84500D01*
G01X77940Y80700D02*
X71550D01*
G01X67750Y84500D02*
Y91000D01*
G01D02*
Y95000D01*
G01X79700Y62800D02*
X77100D01*
G01X83060Y66160D02*
X79700Y62800D01*
G01X83060Y73300D02*
Y66160D01*
G01X73450Y62800D02*
X72500Y63750D01*
G01X77100Y62800D02*
X73450D01*
G01X60250Y69500D02*
Y65500D01*
G01X60000Y69750D02*
X60250Y69500D01*
G01X69000Y65000D02*
X66500D01*
G01X70250Y63750D02*
X69000Y65000D01*
G01X72500Y63750D02*
X70250D01*
G01X60750Y65000D02*
X60250Y65500D01*
G01X66500Y65000D02*
X60750D01*
G01X89050Y62800D02*
X92500D01*
G01X85550Y67650D02*
X85600Y67700D01*
G01X85550Y62800D02*
Y67650D01*
G01X82000Y77000D02*
X88750D01*
G01X80500Y78500D02*
X82000Y77000D01*
G01X80500Y80700D02*
Y78500D01*
G01X88750Y70850D02*
Y72400D01*
G01X85600Y67700D02*
X88750Y70850D01*
G01Y77000D02*
Y72400D01*
G01X77300Y67250D02*
X72500D01*
G01X80500Y70450D02*
X77300Y67250D01*
G01X80500Y73300D02*
Y70450D01*
G01X66000Y106250D02*
X60250Y100500D01*
G01X66000Y111500D02*
Y106250D01*
G01X60250Y96500D02*
Y100500D01*
G01X67750Y101250D02*
Y95000D01*
G01X74000Y107500D02*
X67750Y101250D01*
G01X74000Y113500D02*
Y107500D01*
G01X93300Y236100D02*
Y394500D01*
G01X111066Y218334D02*
X93300Y236100D01*
G01X58709Y376696D02*
Y372346D01*
G01Y383528D02*
Y376696D01*
G01Y389378D02*
Y383528D01*
G01X84495Y403305D02*
X73442D01*
G01X93300Y394500D02*
X84495Y403305D01*
G01X73442D02*
Y396596D01*
G01X86850Y516800D02*
Y520600D01*
G01X88550Y527100D02*
Y525300D01*
G01X88750Y527300D02*
X88550Y527100D01*
G01X88750Y529500D02*
Y527300D01*
G01X86850Y523600D02*
Y520600D01*
G01X88550Y525300D02*
X86850Y523600D01*
G01X82000Y529500D02*
X88750D01*
G01X80500Y531000D02*
X82000Y529500D01*
G01X80500Y533200D02*
Y531000D01*
G01X90350Y516800D02*
X93800D01*
G01X80350Y515100D02*
X77200D01*
G01X83060Y517810D02*
X80350Y515100D01*
G01X83060Y525800D02*
Y517810D01*
G01X76250Y515100D02*
X77200D01*
G01X75100Y516250D02*
X76250Y515100D01*
G01X72500Y516250D02*
X75100D01*
G01X60000Y518250D02*
X60250Y518000D01*
G01X60000Y522250D02*
Y518250D01*
G01X69000Y517500D02*
X66500D01*
G01X70250Y516250D02*
X69000Y517500D01*
G01X72500Y516250D02*
X70250D01*
G01X60750Y517500D02*
X60250Y518000D01*
G01X66500Y517500D02*
X60750D01*
G01X77300Y519750D02*
X72500D01*
G01X80500Y522950D02*
X77300Y519750D01*
G01X80500Y525800D02*
Y522950D01*
G01X67750Y537350D02*
X68100Y537000D01*
G01X67750Y543500D02*
Y537350D01*
G01X71900Y533200D02*
X68100Y537000D01*
G01X77940Y533200D02*
X71900D01*
G01X67750Y553750D02*
Y547500D01*
G01X74000Y560000D02*
X67750Y553750D01*
G01X74000Y566000D02*
Y560000D01*
G01X67750Y547500D02*
Y543500D01*
G01X65750Y525750D02*
X60000D01*
G01X66500Y526500D02*
X65750Y525750D01*
G01X60250Y534000D02*
Y549000D01*
G01X60000Y533750D02*
X60250Y534000D01*
G01X60000Y532500D02*
Y533750D01*
G01X66000Y558750D02*
X60250Y553000D01*
G01X66000Y564000D02*
Y558750D01*
G01X60250Y549000D02*
Y553000D01*
G01X60000Y525750D02*
Y532500D01*
G01X59993Y662515D02*
X125500D01*
G01X43865Y678643D02*
X59993Y662515D01*
G01X60357Y665015D02*
X252000D01*
G01X45890Y679482D02*
X60357Y665015D01*
G01X43865Y799379D02*
Y678643D01*
G01X47915Y680321D02*
Y801057D01*
G01X60761Y667475D02*
X47915Y680321D01*
G01X371000Y667475D02*
X60761D01*
G01X45890Y800218D02*
Y679482D01*
G01X46442Y829350D02*
Y825000D01*
G01Y829350D02*
Y836182D01*
G01D02*
Y842032D01*
G01X26680Y816564D02*
X43865Y799379D01*
G01X26680Y851338D02*
Y816564D01*
G01X40842Y865500D02*
X26680Y851338D01*
G01X86541Y855959D02*
X61175D01*
G01X95000Y847500D02*
X86541Y855959D01*
G01X133099Y847500D02*
X95000D01*
G01X61175Y855959D02*
Y849250D01*
G01X98475Y854025D02*
X133896D01*
G01X91050Y861450D02*
X98475Y854025D01*
G01X30732Y849661D02*
X42521Y861450D01*
G01X30732Y818240D02*
Y849661D01*
G01X47915Y801057D02*
X30732Y818240D01*
G01X28707Y817401D02*
X45890Y800218D01*
G01X28707Y850500D02*
Y817401D01*
G01X41682Y863475D02*
X28707Y850500D01*
G01X102000Y865500D02*
X40842D01*
G01X42521Y861450D02*
X91050D01*
G01X94525Y863475D02*
X41682D01*
G01X100950Y857050D02*
X94525Y863475D01*
G01X83000Y969500D02*
Y970000D01*
G01X84500Y968000D02*
X83000Y969500D01*
G01X88750Y968000D02*
X84500D01*
G01X82000Y982500D02*
X88750D01*
G01X80500Y984000D02*
X82000Y982500D01*
G01X80500Y986200D02*
Y984000D01*
G01X83000Y971576D02*
Y970000D01*
G01X83924Y972500D02*
X83000Y971576D01*
G01X88750Y972500D02*
X83924D01*
G01X88750Y982500D02*
Y972500D01*
G01X77300Y972750D02*
X72500D01*
G01X80500Y975950D02*
X77300Y972750D01*
G01X80500Y978800D02*
Y975950D01*
G01X92250Y968000D02*
X95500D01*
G01X71800Y986200D02*
X69000Y989000D01*
G01X77940Y986200D02*
X71800D01*
G01X67750Y990250D02*
Y996500D01*
G01X69000Y989000D02*
X67750Y990250D01*
G01Y1006750D02*
Y1000500D01*
G01X74000Y1013000D02*
X67750Y1006750D01*
G01X74000Y1019000D02*
Y1013000D01*
G01X67750Y996500D02*
Y1000500D01*
G01X65750Y978750D02*
X60000D01*
G01X66500Y979500D02*
X65750Y978750D01*
G01X60250Y987000D02*
Y1002000D01*
G01X60000Y986750D02*
X60250Y987000D01*
G01X60000Y985500D02*
Y986750D01*
G01X66000Y1011750D02*
X60250Y1006000D01*
G01X66000Y1017000D02*
Y1011750D01*
G01X60250Y1002000D02*
Y1006000D01*
G01X60000Y978750D02*
Y985500D01*
G01X61500Y964500D02*
X63000D01*
G01X60250Y965750D02*
X61500Y964500D01*
G01X60250Y971000D02*
Y965750D01*
G01X65500Y964500D02*
X63000D01*
G01X66500Y965500D02*
X65500Y964500D01*
G01X66500Y970500D02*
Y965500D01*
G01X60000Y971250D02*
X60250Y971000D01*
G01X60000Y975250D02*
Y971250D01*
G01X70250Y969250D02*
X72500D01*
G01X69000Y970500D02*
X70250Y969250D01*
G01X66500Y970500D02*
X69000D01*
G01X77810Y969250D02*
X72500D01*
G01X83060Y974500D02*
X77810Y969250D01*
G01X83060Y978800D02*
Y974500D01*
G01X148911Y36911D02*
X149300Y37300D01*
G01X140428Y36911D02*
X148911D01*
G01X138936Y35419D02*
X140428Y36911D01*
G01X133981Y35419D02*
X138936D01*
G01X132381Y37019D02*
X133981Y35419D01*
G01X132381Y40886D02*
Y37019D01*
G01X193500Y84250D02*
X195250Y82500D01*
G01X193500Y110500D02*
Y84250D01*
G01X151160Y18685D02*
Y18699D01*
G01X150000Y17525D02*
X151160Y18685D01*
G01X137750Y17525D02*
X150000D01*
G01X134941Y20334D02*
X137750Y17525D01*
G01X134941Y24706D02*
Y20334D01*
G01X163450Y29200D02*
X160550Y32100D01*
G01X168350Y29200D02*
X163450D01*
G01X151160Y24938D02*
Y18699D01*
G01X156185Y29963D02*
X151160Y24938D01*
G01X158413Y29963D02*
X156185D01*
G01X160550Y32100D02*
X158413Y29963D01*
G01X171950Y25300D02*
X168100D01*
G01X172150Y25100D02*
X171950Y25300D01*
G01X164250Y25115D02*
Y25100D01*
G01X161427Y27938D02*
X164250Y25115D01*
G01X157024Y27938D02*
X161427D01*
G01X153500Y24414D02*
X157024Y27938D01*
G01X153500Y17173D02*
Y24414D01*
G01X151827Y15500D02*
X153500Y17173D01*
G01X136900Y15500D02*
X151827D01*
G01X132381Y20019D02*
X136900Y15500D01*
G01X132381Y24706D02*
Y20019D01*
G01X167900Y25100D02*
X168100Y25300D01*
G01X164250Y25100D02*
X167900D01*
G01X171750Y20500D02*
X168200D01*
G01X172150Y20900D02*
X171750Y20500D01*
G01X164250Y17650D02*
Y21100D01*
G01X160075Y13475D02*
X164250Y17650D01*
G01X135240Y13475D02*
X160075D01*
G01X129821Y18894D02*
X135240Y13475D01*
G01X129821Y24706D02*
Y18894D01*
G01X167600Y21100D02*
X168200Y20500D01*
G01X164250Y21100D02*
X167600D01*
G01X188841Y81159D02*
Y79022D01*
G01X188500Y81500D02*
X188841Y81159D01*
G01X188500Y86000D02*
Y81500D01*
G01X188841Y72259D02*
X198800Y62300D01*
G01X188841Y79022D02*
Y72259D01*
G01X140450Y126150D02*
X136200D01*
G01X140500Y126100D02*
X140450Y126150D01*
G01X136200D02*
X131600D01*
G01X125300Y126319D02*
X118209D01*
G01X125469Y126150D02*
X125300Y126319D01*
G01X127600Y126150D02*
X125469D01*
G01X131600D02*
X127600D01*
G01X140500Y132100D02*
Y194607D01*
G01X196500Y113500D02*
X193500Y110500D01*
G01X136866Y156319D02*
X118209D01*
G01X162202Y216309D02*
X446366D01*
G01X140500Y194607D02*
X162202Y216309D01*
G01X440533Y218334D02*
X111066D01*
G01X192842Y376350D02*
Y372000D01*
G01Y383182D02*
Y376350D01*
G01Y389032D02*
Y383182D01*
G01X195948Y533200D02*
X192499Y536649D01*
G01X191750Y537398D02*
Y543500D01*
G01X192499Y536649D02*
X191750Y537398D01*
G01Y553750D02*
Y547500D01*
G01X198000Y560000D02*
X191750Y553750D01*
G01Y543500D02*
Y547500D01*
G01X189750Y525750D02*
X184000D01*
G01X190500Y526500D02*
X189750Y525750D01*
G01X184250Y534000D02*
Y549000D01*
G01X184000Y533750D02*
X184250Y534000D01*
G01X184000Y532500D02*
Y533750D01*
G01X190000Y558750D02*
X184250Y553000D01*
G01X190000Y564000D02*
Y558750D01*
G01X184250Y549000D02*
Y553000D01*
G01X184000Y525750D02*
Y532500D01*
G01Y518250D02*
X184250Y518000D01*
G01X184000Y522250D02*
Y518250D01*
G01X193000Y517500D02*
X190500D01*
G01X194250Y516250D02*
X193000Y517500D01*
G01X196500Y516250D02*
X194250D01*
G01X184750Y517500D02*
X184250Y518000D01*
G01X190500Y517500D02*
X184750D01*
G01X143500Y644515D02*
Y594500D01*
G01X125500Y662515D02*
X143500Y644515D01*
G01X118209Y609075D02*
X136866D01*
G01X137250Y583000D02*
Y588500D01*
G01Y579000D02*
Y583000D01*
G01X137500Y588750D02*
X137250Y588500D01*
G01X137500Y594500D02*
Y588750D01*
G01X137175Y579075D02*
X118209D01*
G01X137250Y579000D02*
X137175Y579075D01*
G01X149677Y864078D02*
X133099Y847500D01*
G01X169442Y829050D02*
Y824700D01*
G01X172444Y837032D02*
X173558Y835918D01*
G01X167842Y837032D02*
X172444D01*
G01X173558Y833166D02*
X169442Y829050D01*
G01X173558Y835918D02*
Y833166D01*
G01X133896Y854025D02*
X147999Y868128D01*
G01X184175Y859980D02*
Y855659D01*
G01D02*
Y849250D01*
G01X107425Y860075D02*
X102000Y865500D01*
G01X134218Y860075D02*
X107425D01*
G01X146321Y872178D02*
X134218Y860075D01*
G01X195468Y872178D02*
X146321D01*
G01X198824Y864078D02*
X149677D01*
G01X147999Y868128D02*
X197146D01*
G01X186248Y862053D02*
X184175Y859980D01*
G01X199663Y862053D02*
X186248D01*
G01X134057Y857050D02*
X100950D01*
G01X147160Y870153D02*
X134057Y857050D01*
G01X196307Y870153D02*
X147160D01*
G01X190250Y978750D02*
X184500D01*
G01X191000Y979500D02*
X190250Y978750D01*
G01X184750Y987000D02*
Y1002000D01*
G01X184500Y986750D02*
X184750Y987000D01*
G01X184500Y985500D02*
Y986750D01*
G01X190500Y1011750D02*
X184750Y1006000D01*
G01X190500Y1017000D02*
Y1011750D01*
G01X184750Y1002000D02*
Y1006000D01*
G01X184500Y978750D02*
Y985500D01*
G01X196846Y986200D02*
X193949Y989097D01*
G01X192250Y990796D02*
Y996500D01*
G01X193949Y989097D02*
X192250Y990796D01*
G01Y1006750D02*
Y1000500D01*
G01X198500Y1013000D02*
X192250Y1006750D01*
G01Y996500D02*
Y1000500D01*
G01X184500Y971250D02*
X184750Y971000D01*
G01X184500Y975250D02*
Y971250D01*
G01X193500Y970500D02*
X191000D01*
G01X194750Y969250D02*
X193500Y970500D01*
G01X197000Y969250D02*
X194750D01*
G01X185250Y970500D02*
X184750Y971000D01*
G01X191000Y970500D02*
X185250D01*
G01X137500Y1041750D02*
X137250Y1041500D01*
G01X137500Y1047500D02*
Y1041750D01*
G01X137250Y1036000D02*
Y1041500D01*
G01Y1032000D02*
Y1036000D01*
G01X137081Y1031831D02*
X118209D01*
G01X137250Y1032000D02*
X137081Y1031831D01*
G01X159500Y1127740D02*
X768086D01*
G01X143500Y1111740D02*
X159500Y1127740D01*
G01X143500Y1047500D02*
Y1111740D01*
G01X118209Y1061831D02*
X136866D01*
G01X139661Y1478250D02*
X139374D01*
G01X141266Y1476645D02*
X139661Y1478250D01*
G01X149202Y1476645D02*
X141266D01*
G01X150807Y1478250D02*
X149202Y1476645D01*
G01X150953Y1478250D02*
X150807D01*
G01X152565Y1479862D02*
X150953Y1478250D01*
G01X187854Y1479862D02*
X152565D01*
G01X200787Y1466929D02*
X187854Y1479862D01*
G01X134710Y1478250D02*
X139374D01*
G01X131036Y1474576D02*
X134710Y1478250D01*
G01X131036Y1448762D02*
Y1474576D01*
G01X124874Y1442600D02*
X131036Y1448762D01*
G01X220000Y77250D02*
Y80500D01*
G01X207250Y45100D02*
X211162D01*
G01X218350Y64410D02*
Y57400D01*
G01X214700Y68060D02*
X218350Y64410D01*
G01X210700Y68060D02*
X214700D01*
G01X213995Y45250D02*
X217000D01*
G01X213845Y45100D02*
X213995Y45250D01*
G01X211162Y45100D02*
X213845D01*
G01X217500Y54000D02*
Y51200D01*
G01X218350Y54850D02*
X217500Y54000D01*
G01X218350Y57400D02*
Y54850D01*
G01X217000Y48032D02*
Y45250D01*
G01X217500Y48532D02*
X217000Y48032D01*
G01X217500Y51200D02*
Y48532D01*
G01X195250Y72500D02*
Y73500D01*
G01X200000Y67750D02*
X195250Y72500D01*
G01X200000Y64500D02*
Y67750D01*
G01X201560Y62940D02*
X200000Y64500D01*
G01X203300Y62940D02*
X201560D01*
G01X195250Y73500D02*
Y78500D01*
G01D02*
Y82500D01*
G01X208200Y57400D02*
X211000D01*
G01X207100Y58500D02*
X208200Y57400D01*
G01X207100Y64100D02*
Y58500D01*
G01X208500Y65500D02*
X207100Y64100D01*
G01X210700Y65500D02*
X208500D01*
G01X211000Y57400D02*
X214850D01*
G01X203750Y48583D02*
Y45100D01*
G01X206367Y51200D02*
X203750Y48583D01*
G01X208500Y51200D02*
X206367D01*
G01X198800Y62300D02*
Y40950D01*
G01D02*
X202800D01*
G01X203750Y41900D02*
X202800Y40950D01*
G01X203750Y45100D02*
Y41900D01*
G01X220000Y73750D02*
X215500D01*
G01X211086D02*
X215500D01*
G01X207000Y67000D02*
Y73750D01*
G01X205500Y65500D02*
X207000Y67000D01*
G01X203300Y65500D02*
X205500D01*
G01X207000Y73750D02*
X211086D01*
G01X242421Y156319D02*
X261078D01*
G01X264850Y126350D02*
X260400D01*
G01X265000Y126200D02*
X264850Y126350D01*
G01X260400D02*
X254900D01*
G01X247836Y126319D02*
X242421D01*
G01X247867Y126350D02*
X247836Y126319D01*
G01X250900Y126350D02*
X247867D01*
G01X254900D02*
X250900D01*
G01X198000Y113500D02*
X196500D01*
G01X267279Y145832D02*
Y212130D01*
G01X265000Y143553D02*
X267279Y145832D01*
G01X265000Y132200D02*
Y143553D01*
G01X230700Y229800D02*
Y395244D01*
G01X240141Y220359D02*
X230700Y229800D01*
G01X434699Y220359D02*
X240141D01*
G01X269432Y214283D02*
X451058D01*
G01X267279Y212130D02*
X269432Y214283D01*
G01X222985Y402959D02*
X207575D01*
G01X230700Y395244D02*
X222985Y402959D01*
G01X207575D02*
Y396350D01*
G01X211150Y520500D02*
Y516600D01*
G01X212650Y526800D02*
Y525200D01*
G01X212750Y526900D02*
X212650Y526800D01*
G01X212750Y529500D02*
Y526900D01*
G01X211150Y523700D02*
Y520500D01*
G01X212650Y525200D02*
X211150Y523700D01*
G01X206000Y529500D02*
X212750D01*
G01X204500Y531000D02*
X206000Y529500D01*
G01X204500Y533200D02*
Y531000D01*
G01X201940Y533200D02*
X195948D01*
G01X198000Y566000D02*
Y560000D01*
G01X218000Y516600D02*
X214650D01*
G01X203200Y515300D02*
X201000D01*
G01X207060Y519160D02*
X203200Y515300D01*
G01X207060Y525800D02*
Y519160D01*
G01X197450Y515300D02*
X201000D01*
G01X196500Y516250D02*
X197450Y515300D01*
G01X201300Y519750D02*
X196500D01*
G01X204500Y522950D02*
X201300Y519750D01*
G01X204500Y525800D02*
Y522950D01*
G01X261250Y579000D02*
Y583000D01*
G01Y588500D02*
Y583000D01*
G01X261500Y588750D02*
X261250Y588500D01*
G01X261500Y594500D02*
Y588750D01*
G01X261175Y579075D02*
X242421D01*
G01X261250Y579000D02*
X261175Y579075D01*
G01X261078Y609075D02*
X242421D01*
G01X267500Y649515D02*
Y594500D01*
G01X252000Y665015D02*
X267500Y649515D01*
G01X244214Y920924D02*
X195468Y872178D01*
G01X244214Y920925D02*
Y920924D01*
G01X245399Y922110D02*
X244214Y920925D01*
G01X755389Y922110D02*
X245399D01*
G01X216159Y881413D02*
X198824Y864078D01*
G01X794067Y881413D02*
X216159D01*
G01X246793Y917775D02*
X448289D01*
G01X197146Y868128D02*
X246793Y917775D01*
G01X216998Y879388D02*
X199663Y862053D01*
G01X782721Y879388D02*
X216998D01*
G01X246239Y920085D02*
X196307Y870153D01*
G01X759068Y920085D02*
X246239D01*
G01X201800Y972750D02*
X197000D01*
G01X205000Y975950D02*
X201800Y972750D01*
G01X205000Y978800D02*
Y975950D01*
G01X218100Y969700D02*
X214350D01*
G01X202440Y986200D02*
X196846D01*
G01X198500Y1019000D02*
Y1013000D01*
G01X203400Y968400D02*
X201600D01*
G01X207560Y972560D02*
X203400Y968400D01*
G01X207560Y978800D02*
Y972560D01*
G01X197850Y968400D02*
X201600D01*
G01X197000Y969250D02*
X197850Y968400D01*
G01X267200Y1047500D02*
X269085Y1049385D01*
G01X210850Y975700D02*
Y973800D01*
G01X213250Y978100D02*
X210850Y975700D01*
G01Y973800D02*
Y969700D01*
G01X206500Y982500D02*
X213250D01*
G01X205000Y984000D02*
X206500Y982500D01*
G01X205000Y986200D02*
Y984000D01*
G01X213250Y982500D02*
Y978100D01*
G01X261200Y1042300D02*
X261500Y1042000D01*
G01X261200Y1047500D02*
Y1042300D01*
G01X260950Y1041450D02*
X261500Y1042000D01*
G01X260950Y1036000D02*
Y1041450D01*
G01Y1032000D02*
Y1036000D01*
G01X260781Y1031831D02*
X242421D01*
G01X260950Y1032000D02*
X260781Y1031831D01*
G01X242421Y1061831D02*
X261078D01*
G01X272896Y1125576D02*
X764039D01*
G01X269085Y1121765D02*
X272896Y1125576D01*
G01X269085Y1049385D02*
Y1121765D01*
G01X320100Y80700D02*
X316800Y84000D01*
G01X326440Y80700D02*
X320100D01*
G01X316250Y84550D02*
Y91000D01*
G01X316800Y84000D02*
X316250Y84550D01*
G01Y91000D02*
Y95000D01*
G01X328400Y62900D02*
X325900D01*
G01X329700Y64200D02*
X328400Y62900D01*
G01X329700Y67840D02*
Y64200D01*
G01X331560Y69700D02*
X329700Y67840D01*
G01X331560Y73300D02*
Y69700D01*
G01X321850Y62900D02*
X321000Y63750D01*
G01X325900Y62900D02*
X321850D01*
G01X308500Y65750D02*
X308750Y65500D01*
G01X308500Y69750D02*
Y65750D01*
G01X317500Y65000D02*
X315000D01*
G01X318750Y63750D02*
X317500Y65000D01*
G01X321000Y63750D02*
X318750D01*
G01X309250Y65000D02*
X308750Y65500D01*
G01X315000Y65000D02*
X309250D01*
G01X314250Y73250D02*
X308500D01*
G01X315000Y74000D02*
X314250Y73250D01*
G01X308750Y81500D02*
Y96500D01*
G01X308500Y81250D02*
X308750Y81500D01*
G01X308500Y80000D02*
Y81250D01*
G01Y73250D02*
Y80000D01*
G01X338450Y63700D02*
X341800D01*
G01X330500Y77000D02*
X337250D01*
G01X329000Y78500D02*
X330500Y77000D01*
G01X329000Y80700D02*
Y78500D01*
G01X335100Y65431D02*
Y67800D01*
G01X334950Y65281D02*
X335100Y65431D01*
G01X334950Y63700D02*
Y65281D01*
G01X337150Y71224D02*
Y72600D01*
G01X335100Y69174D02*
X337150Y71224D01*
G01X335100Y67800D02*
Y69174D01*
G01X337150Y74609D02*
Y72600D01*
G01X337250Y74709D02*
X337150Y74609D01*
G01X337250Y77000D02*
Y74709D01*
G01X325800Y67250D02*
X321000D01*
G01X329000Y70450D02*
X325800Y67250D01*
G01X329000Y73300D02*
Y70450D01*
G01X366634Y156319D02*
X385291D01*
G01X316250Y101250D02*
Y95000D01*
G01X322500Y107500D02*
X316250Y101250D01*
G01X322500Y113500D02*
Y107500D01*
G01X384549Y126350D02*
X379500D01*
G01X388950D02*
X384549D01*
G01X372195Y126319D02*
X366634D01*
G01X372226Y126350D02*
X372195Y126319D01*
G01X375500Y126350D02*
X372226D01*
G01X379500D02*
X375500D01*
G01X314500Y106250D02*
X308750Y100500D01*
G01X314500Y111500D02*
Y106250D01*
G01X308750Y96500D02*
Y100500D01*
G01X339300Y236700D02*
Y393729D01*
G01X353616Y222384D02*
X339300Y236700D01*
G01X429627Y222384D02*
X353616D01*
G01X294542Y376650D02*
Y372300D01*
G01Y383482D02*
Y376650D01*
G01Y389332D02*
Y383482D01*
G01X329770Y403259D02*
X309275D01*
G01X339300Y393729D02*
X329770Y403259D01*
G01X309275D02*
Y396550D01*
G01X320958Y533200D02*
X326440D01*
G01X316250Y536050D02*
Y543500D01*
G01X319100Y533200D02*
X316250Y536050D01*
G01X320958Y533200D02*
X319100D01*
G01X316250Y553750D02*
Y547500D01*
G01X322500Y560000D02*
X316250Y553750D01*
G01X322500Y566000D02*
Y560000D01*
G01X316250Y543500D02*
Y547500D01*
G01X328450Y514700D02*
X325800D01*
G01X331560Y517810D02*
X328450Y514700D01*
G01X331560Y525800D02*
Y517810D01*
G01X308500Y518250D02*
X308750Y518000D01*
G01X308500Y522250D02*
Y518250D01*
G01X323700Y514700D02*
X325800D01*
G01X322150Y516250D02*
X323700Y514700D01*
G01X321000Y516250D02*
X322150D01*
G01X317500Y517500D02*
X315000D01*
G01X318750Y516250D02*
X317500Y517500D01*
G01X321000Y516250D02*
X318750D01*
G01X309250Y517500D02*
X308750Y518000D01*
G01X315000Y517500D02*
X309250D01*
G01X335050Y523100D02*
Y520700D01*
G01X337250Y525300D02*
X335050Y523100D01*
G01Y520700D02*
Y516800D01*
G01X330500Y529500D02*
X337250D01*
G01X329000Y531000D02*
X330500Y529500D01*
G01X329000Y533200D02*
Y531000D01*
G01X337250Y529500D02*
Y525300D01*
G01X325800Y519750D02*
X321000D01*
G01X329000Y522950D02*
X325800Y519750D01*
G01X329000Y525800D02*
Y522950D01*
G01X341800Y516800D02*
X338550D01*
G01X314250Y525750D02*
X308500D01*
G01X315000Y526500D02*
X314250Y525750D01*
G01X308750Y534000D02*
Y549000D01*
G01X308500Y533750D02*
X308750Y534000D01*
G01X308500Y532500D02*
Y533750D01*
G01X314500Y558750D02*
X308750Y553000D01*
G01X314500Y564000D02*
Y558750D01*
G01X308750Y549000D02*
Y553000D01*
G01X308500Y525750D02*
Y532500D01*
G01X366634Y609075D02*
X385291D01*
G01X392000Y646475D02*
X371000Y667475D01*
G01X386000Y588750D02*
X385750Y588500D01*
G01X385675Y579075D02*
X366634D01*
G01X385750Y579000D02*
X385675Y579075D01*
G01X309275Y865111D02*
Y855959D01*
G01D02*
Y849250D01*
G01X294542Y829350D02*
Y825000D01*
G01Y829350D02*
Y836182D01*
G01D02*
Y842032D01*
G01X321527Y877363D02*
X312418Y868254D01*
G01X777426Y877363D02*
X321527D01*
G01X312418Y868254D02*
X309275Y865111D01*
G01X320073Y986200D02*
X317542Y988731D01*
G01X326440Y986200D02*
X320073D01*
G01X316250Y990023D02*
Y996500D01*
G01X317542Y988731D02*
X316250Y990023D01*
G01Y1006750D02*
Y1000500D01*
G01X322500Y1013000D02*
X316250Y1006750D01*
G01X322500Y1019000D02*
Y1013000D01*
G01X316250Y996500D02*
Y1000500D01*
G01X314250Y978750D02*
X308500D01*
G01X315000Y979500D02*
X314250Y978750D01*
G01X308750Y987000D02*
Y1002000D01*
G01X308500Y986750D02*
X308750Y987000D01*
G01X308500Y985500D02*
Y986750D01*
G01X314500Y1011750D02*
X308750Y1006000D01*
G01X314500Y1017000D02*
Y1011750D01*
G01X308750Y1002000D02*
Y1006000D01*
G01X308500Y978750D02*
Y985500D01*
G01X386000Y1041750D02*
X385750Y1041500D01*
G01X385581Y1031831D02*
X366634D01*
G01X385750Y1032000D02*
X385581Y1031831D01*
G01X325800Y972750D02*
X321000D01*
G01X329000Y975950D02*
X325800Y972750D01*
G01X329000Y978800D02*
Y975950D01*
G01X334750Y973200D02*
Y969400D01*
G01X337150Y982400D02*
Y978200D01*
G01X337250Y982500D02*
X337150Y982400D01*
G01X334750Y975800D02*
Y973200D01*
G01X337150Y978200D02*
X334750Y975800D01*
G01X330500Y982500D02*
X337250D01*
G01X329000Y984000D02*
X330500Y982500D01*
G01X329000Y986200D02*
Y984000D01*
G01X327160Y968400D02*
X325600D01*
G01X331560Y972800D02*
X327160Y968400D01*
G01X331560Y978800D02*
Y972800D01*
G01X321850Y968400D02*
X325600D01*
G01X321000Y969250D02*
X321850Y968400D01*
G01X308500Y971250D02*
X308750Y971000D01*
G01X308500Y975250D02*
Y971250D01*
G01X317500Y970500D02*
X315000D01*
G01X318750Y969250D02*
X317500Y970500D01*
G01X321000Y969250D02*
X318750D01*
G01X309250Y970500D02*
X308750Y971000D01*
G01X315000Y970500D02*
X309250D01*
G01X341900Y969400D02*
X338250D01*
G01X366634Y1061831D02*
X385291D01*
G01X458450Y77150D02*
X458900Y76700D01*
G01X454000Y77150D02*
X458450D01*
G01X461850Y73750D02*
X464000D01*
G01X458900Y76700D02*
X461850Y73750D01*
G01X464000D02*
X468500D01*
G01X454000Y67000D02*
Y77150D01*
G01X452500Y65500D02*
X454000Y67000D01*
G01X450300Y65500D02*
X452500D01*
G01X456100Y57500D02*
X459000D01*
G01X454100Y59500D02*
X456100Y57500D01*
G01X454100Y64100D02*
Y59500D01*
G01X455500Y65500D02*
X454100Y64100D01*
G01X457700Y65500D02*
X455500D01*
G01X459000Y57500D02*
X463750D01*
G01X464750Y44500D02*
X459511D01*
G01X465500Y45250D02*
X464750Y44500D01*
G01X459511D02*
X455450D01*
G01X466000Y54000D02*
Y51500D01*
G01X467250Y55250D02*
X466000Y54000D01*
G01X467250Y57500D02*
Y55250D01*
G01X466000Y45750D02*
X465500Y45250D01*
G01X466000Y51500D02*
Y45750D01*
G01X467250Y63150D02*
Y57500D01*
G01X462340Y68060D02*
X467250Y63150D01*
G01X457700Y68060D02*
X462340D01*
G01X445500Y76800D02*
Y74300D01*
G01X441800Y80500D02*
X445500Y76800D01*
G01X441800Y106683D02*
Y80500D01*
G01X445500Y64500D02*
Y74300D01*
G01X447060Y62940D02*
X445500Y64500D01*
G01X450300Y62940D02*
X447060D01*
G01X468500Y77250D02*
Y80500D01*
G01X444400Y39250D02*
X440400D01*
G01X447300D02*
X448200Y40150D01*
G01X444400Y39250D02*
X447300D01*
G01X451950Y47550D02*
Y44500D01*
G01X455900Y51500D02*
X451950Y47550D01*
G01X457000Y51500D02*
X455900D01*
G01X451950Y43900D02*
X448200Y40150D01*
G01X451950Y44500D02*
Y43900D01*
G01X440500Y39350D02*
X440400Y39250D01*
G01X440500Y46600D02*
Y39350D01*
G01X389000Y126400D02*
X388950Y126350D01*
G01X389000Y144367D02*
X511136Y266503D01*
G01X389000Y132400D02*
Y144367D01*
G01X435100Y113383D02*
X441800Y106683D01*
G01X435100Y118850D02*
Y113383D01*
G01X442550Y118850D02*
X440849D01*
G01X444300Y117100D02*
X442550Y118850D01*
G01X446900Y117100D02*
X444300D01*
G01X440849Y118850D02*
X435100D01*
G01X488448Y274108D02*
X434699Y220359D01*
G01X482745Y275502D02*
X429627Y222384D01*
G01X446366Y216309D02*
X498968Y268911D01*
G01X493899Y271700D02*
X440533Y218334D01*
G01X451058Y214283D02*
X505052Y268277D01*
G01X419042Y376350D02*
Y372000D01*
G01Y383182D02*
Y376350D01*
G01Y389032D02*
Y383182D01*
G01X435190Y408695D02*
X493149Y466654D01*
G01X433775Y407280D02*
Y402959D01*
G01X435190Y408695D02*
X433775Y407280D01*
G01Y402959D02*
Y396350D01*
G01X459350Y520600D02*
Y516900D01*
G01X454500Y529500D02*
X461250D01*
G01X453000Y531000D02*
X454500Y529500D01*
G01X453000Y533200D02*
Y531000D01*
G01X459350Y523400D02*
X461250Y525300D01*
G01X459350Y520600D02*
Y523400D01*
G01X461250Y529500D02*
Y525300D01*
G01X443669Y533200D02*
X440855Y536014D01*
G01X450440Y533200D02*
X443669D01*
G01X440250Y536619D02*
Y543500D01*
G01X440855Y536014D02*
X440250Y536619D01*
G01Y553750D02*
Y547500D01*
G01X446500Y560000D02*
X440250Y553750D01*
G01X446500Y566000D02*
Y560000D01*
G01X440250Y543500D02*
Y547500D01*
G01X466000Y516900D02*
X462850D01*
G01X451500Y515400D02*
X449800D01*
G01X455560Y519460D02*
X451500Y515400D01*
G01X455560Y525800D02*
Y519460D01*
G01X445850Y515400D02*
X445000Y516250D01*
G01X449800Y515400D02*
X445850D01*
G01X432622Y518128D02*
X432750Y518000D01*
G01X432622Y522128D02*
Y518128D01*
G01X432500Y522250D02*
X432622Y522128D01*
G01X441500Y517500D02*
X439000D01*
G01X442750Y516250D02*
X441500Y517500D01*
G01X445000Y516250D02*
X442750D01*
G01X435974Y518000D02*
X432750D01*
G01X436474Y517500D02*
X435974Y518000D01*
G01X439000Y517500D02*
X436474D01*
G01X438250Y525750D02*
X432500D01*
G01X439000Y526500D02*
X438250Y525750D01*
G01X432750Y534000D02*
Y549000D01*
G01X432500Y533750D02*
X432750Y534000D01*
G01X432500Y532500D02*
Y533750D01*
G01X438500Y558750D02*
X432750Y553000D01*
G01X438500Y564000D02*
Y558750D01*
G01X432750Y549000D02*
Y553000D01*
G01X432500Y525750D02*
Y532500D01*
G01X449800Y519750D02*
X445000D01*
G01X453000Y522950D02*
X449800Y519750D01*
G01X453000Y525800D02*
Y522950D01*
G01X392000Y594500D02*
Y646475D01*
G01X385750Y583000D02*
Y588500D01*
G01Y579000D02*
Y583000D01*
G01X386000Y594500D02*
Y588750D01*
G01X418742Y828794D02*
Y824444D01*
G01Y828794D02*
Y835876D01*
G01D02*
Y841732D01*
G01X433475Y859980D02*
Y855659D01*
G01D02*
Y849050D01*
G01X448833Y875338D02*
X434890Y861395D01*
G01X776587Y875338D02*
X448833D01*
G01X434890Y861395D02*
X433475Y859980D01*
G01X762537Y917775D02*
X448289D01*
G01X459150Y973500D02*
Y969200D01*
G01X461150Y980034D02*
Y978000D01*
G01X461250Y980134D02*
X461150Y980034D01*
G01X461250Y982500D02*
Y980134D01*
G01X459150Y976000D02*
Y973500D01*
G01X461150Y978000D02*
X459150Y976000D01*
G01X454500Y982500D02*
X461250D01*
G01X453000Y984000D02*
X454500Y982500D01*
G01X453000Y986200D02*
Y984000D01*
G01X385750Y1032000D02*
Y1036000D01*
G01D02*
Y1041500D01*
G01X386000Y1047500D02*
Y1041750D01*
G01X444566Y986200D02*
X441398Y989368D01*
G01X450440Y986200D02*
X444566D01*
G01X440250Y990516D02*
Y996500D01*
G01X441398Y989368D02*
X440250Y990516D01*
G01Y1006750D02*
Y1000500D01*
G01X446500Y1013000D02*
X440250Y1006750D01*
G01X446500Y1019000D02*
Y1013000D01*
G01X440250Y996500D02*
Y1000500D01*
G01X438250Y978750D02*
X432500D01*
G01X439000Y979500D02*
X438250Y978750D01*
G01X432750Y987000D02*
Y1002000D01*
G01X432500Y986750D02*
X432750Y987000D01*
G01X432500Y985500D02*
Y986750D01*
G01X438500Y1011750D02*
X432750Y1006000D01*
G01X438500Y1017000D02*
Y1011750D01*
G01X432750Y1002000D02*
Y1006000D01*
G01X432500Y978750D02*
Y985500D01*
G01X451660Y968500D02*
X449700D01*
G01X455560Y972400D02*
X451660Y968500D01*
G01X455560Y978800D02*
Y972400D01*
G01X445750Y968500D02*
X449700D01*
G01X445000Y969250D02*
X445750Y968500D01*
G01X432500Y971250D02*
X432750Y971000D01*
G01X432500Y975250D02*
Y971250D01*
G01X441500Y970500D02*
X439000D01*
G01X442750Y969250D02*
X441500Y970500D01*
G01X445000Y969250D02*
X442750D01*
G01X433250Y970500D02*
X432750Y971000D01*
G01X439000Y970500D02*
X433250D01*
G01X449800Y972750D02*
X445000D01*
G01X453000Y975950D02*
X449800Y972750D01*
G01X453000Y978800D02*
Y975950D01*
G01X462650Y969200D02*
X466100D01*
G01X395930Y1123550D02*
X761248D01*
G01X392000Y1119620D02*
X395930Y1123550D01*
G01X392000Y1047500D02*
Y1119620D01*
G01X576500Y62900D02*
X574300D01*
G01X580060Y66460D02*
X576500Y62900D01*
G01X572300Y63750D02*
X569500D01*
G01X573150Y62900D02*
X572300Y63750D01*
G01X574300Y62900D02*
X573150D01*
G01X557000Y65750D02*
X557250Y65500D01*
G01X557000Y69750D02*
Y65750D01*
G01X566000Y65000D02*
X563500D01*
G01X567250Y63750D02*
X566000Y65000D01*
G01X569500Y63750D02*
X567250D01*
G01X557750Y65000D02*
X557250Y65500D01*
G01X563500Y65000D02*
X557750D01*
G01X568666Y80700D02*
X565757Y83609D01*
G01X574940Y80700D02*
X568666D01*
G01X564750Y84616D02*
Y91000D01*
G01X565757Y83609D02*
X564750Y84616D01*
G01Y91000D02*
Y95000D01*
G01X574300Y67250D02*
X569500D01*
G01X577500Y70450D02*
X574300Y67250D01*
G01X562750Y73250D02*
X557000D01*
G01X563500Y74000D02*
X562750Y73250D01*
G01X557250Y81500D02*
Y96500D01*
G01X557000Y81250D02*
X557250Y81500D01*
G01X557000Y80000D02*
Y81250D01*
G01Y73250D02*
Y80000D01*
G01X490846Y156319D02*
X509503D01*
G01X517473Y147036D02*
Y332556D01*
G01X513600Y143163D02*
X517473Y147036D01*
G01X513600Y132300D02*
Y143163D01*
G01X564750Y101250D02*
Y95000D01*
G01X571000Y107500D02*
X564750Y101250D01*
G01X571000Y113500D02*
Y107500D01*
G01X503900Y126250D02*
X508761D01*
G01X499900D02*
X503900D01*
G01X513550D02*
X508761D01*
G01X513600Y126300D02*
X513550Y126250D01*
G01X497189Y126319D02*
X490846D01*
G01X497258Y126250D02*
X497189Y126319D01*
G01X499900Y126250D02*
X497258D01*
G01X563000Y106250D02*
X557250Y100500D01*
G01X563000Y111500D02*
Y106250D01*
G01X557250Y96500D02*
Y100500D01*
G01X488448Y338766D02*
Y274108D01*
G01X482745Y351821D02*
Y275502D01*
G01X498968Y268911D02*
Y296814D01*
G01X493899Y320895D02*
Y271700D01*
G01X511136Y266503D02*
Y352328D01*
G01X523810Y256528D02*
Y312530D01*
G01X565655Y214683D02*
X523810Y256528D01*
G01X621677Y214683D02*
X565655D01*
G01X505052Y268277D02*
Y368552D01*
G01X531987Y257983D02*
Y294450D01*
G01X567970Y222000D02*
X531987Y257983D01*
G01X742300Y222000D02*
X567970D01*
G01X488448Y338766D02*
Y412578D01*
G01X517473Y332556D02*
Y403790D01*
G01X482745Y351821D02*
Y414130D01*
G01X498968Y296814D02*
Y407269D01*
G01X493899Y320895D02*
Y410335D01*
G01X543242Y372300D02*
Y376650D01*
G01Y383482D02*
Y376650D01*
G01X511136Y352328D02*
Y404267D01*
G01X523810Y312530D02*
Y403092D01*
G01X505052Y368552D02*
Y404999D01*
G01X531987Y402036D02*
Y294450D01*
G01X534411Y458541D02*
X738032D01*
G01X488448Y412578D02*
X534411Y458541D01*
G01X493149Y466654D02*
X740417D01*
G01X555117Y441434D02*
X735245D01*
G01X517473Y403790D02*
X555117Y441434D01*
G01X530959Y462344D02*
X738971D01*
G01X482745Y414130D02*
X530959Y462344D01*
G01X543776Y452077D02*
X737296D01*
G01X498968Y407269D02*
X543776Y452077D01*
G01X557975Y420549D02*
Y412093D01*
G01X568326Y430900D02*
X557975Y420549D01*
G01X737513Y430900D02*
X568326D01*
G01X557975Y396550D02*
Y403259D01*
G01D02*
Y412093D01*
G01X538937Y455373D02*
X737728D01*
G01X493899Y410335D02*
X538937Y455373D01*
G01X543242Y389332D02*
Y383482D01*
G01X552229Y445360D02*
X736307D01*
G01X511136Y404267D02*
X552229Y445360D01*
G01X558733Y438015D02*
X734690D01*
G01X523810Y403092D02*
X558733Y438015D01*
G01X548452Y448399D02*
X736482D01*
G01X505052Y404999D02*
X548452Y448399D01*
G01X564326Y434375D02*
X531987Y402036D01*
G01X736044Y434375D02*
X564326D01*
G01X562750Y525750D02*
X557000D01*
G01X563500Y526500D02*
X562750Y525750D01*
G01X557250Y534000D02*
Y549000D01*
G01X557000Y533750D02*
X557250Y534000D01*
G01X557000Y532500D02*
Y533750D01*
G01X563000Y558750D02*
X557250Y553000D01*
G01X563000Y564000D02*
Y558750D01*
G01X557250Y549000D02*
Y553000D01*
G01X557000Y525750D02*
Y532500D01*
G01X569300Y533200D02*
X565500Y537000D01*
G01X574940Y533200D02*
X569300D01*
G01X564750Y537750D02*
Y543500D01*
G01X565500Y537000D02*
X564750Y537750D01*
G01Y553750D02*
Y547500D01*
G01X571000Y560000D02*
X564750Y553750D01*
G01X571000Y566000D02*
Y560000D01*
G01X564750Y543500D02*
Y547500D01*
G01X576600Y515500D02*
X574300D01*
G01X580060Y518960D02*
X576600Y515500D01*
G01X570250D02*
X569500Y516250D01*
G01X574300Y515500D02*
X570250D01*
G01X557000Y518250D02*
X557250Y518000D01*
G01X557000Y522250D02*
Y518250D01*
G01X568250Y517500D02*
X563500D01*
G01X569500Y516250D02*
X568250Y517500D01*
G01X557750D02*
X557250Y518000D01*
G01X563500Y517500D02*
X557750D01*
G01X574300Y519750D02*
X569500D01*
G01X577500Y522950D02*
X574300Y519750D01*
G01X490846Y609075D02*
X509503D01*
G01X510000Y588750D02*
X509750Y588500D01*
G01X510000Y594500D02*
Y588750D01*
G01X509750Y588500D02*
Y583000D01*
G01X501017Y579075D02*
X490846D01*
G01X501092Y579000D02*
X501017Y579075D01*
G01X509750Y579000D02*
X501092D01*
G01X509750Y583000D02*
Y579000D01*
G01X516000Y637413D02*
Y594500D01*
G01X576100Y968300D02*
X574200D01*
G01X580060Y972260D02*
X576100Y968300D01*
G01X570450D02*
X574200D01*
G01X569500Y969250D02*
X570450Y968300D01*
G01X557088Y971162D02*
X557250Y971000D01*
G01X557088Y973833D02*
Y971162D01*
G01X557000Y973921D02*
X557088Y973833D01*
G01X557000Y975250D02*
Y973921D01*
G01X566000Y970500D02*
X563500D01*
G01X567250Y969250D02*
X566000Y970500D01*
G01X569500Y969250D02*
X567250D01*
G01X557750Y970500D02*
X557250Y971000D01*
G01X563500Y970500D02*
X557750D01*
G01X509750Y1036000D02*
Y1041500D01*
G01Y1032000D02*
Y1036000D01*
G01X510000Y1041750D02*
X509750Y1041500D01*
G01X510000Y1047500D02*
Y1041750D01*
G01X509581Y1031831D02*
X490846D01*
G01X509750Y1032000D02*
X509581Y1031831D01*
G01X562750Y978750D02*
X557000D01*
G01X563500Y979500D02*
X562750Y978750D01*
G01X557250Y987000D02*
Y1002000D01*
G01X557000Y986750D02*
X557250Y987000D01*
G01X557000Y985500D02*
Y986750D01*
G01X563000Y1011750D02*
X557250Y1006000D01*
G01X563000Y1017000D02*
Y1011750D01*
G01X557250Y1002000D02*
Y1006000D01*
G01X557000Y978750D02*
Y985500D01*
G01X568701Y986200D02*
X566574Y988327D01*
G01X574940Y986200D02*
X568701D01*
G01X564750Y990151D02*
Y996500D01*
G01X566574Y988327D02*
X564750Y990151D01*
G01Y1006750D02*
Y1000500D01*
G01X571000Y1013000D02*
X564750Y1006750D01*
G01X571000Y1019000D02*
Y1013000D01*
G01X564750Y996500D02*
Y1000500D01*
G01X574300Y972750D02*
X569500D01*
G01X577500Y975950D02*
X574300Y972750D01*
G01X518465Y1121525D02*
X755669D01*
G01X516000Y1119060D02*
X518465Y1121525D01*
G01X516000Y1047500D02*
Y1119060D01*
G01X490846Y1061831D02*
X509503D01*
G01X580060Y73300D02*
Y66460D01*
G01X583700Y64350D02*
Y68200D01*
G01X583750Y64300D02*
X583700Y64350D01*
G01Y70850D02*
X585650Y72800D01*
G01X583700Y68200D02*
Y70850D01*
G01X585750Y74900D02*
Y77000D01*
G01X585650Y74800D02*
X585750Y74900D01*
G01X585650Y72800D02*
Y74800D01*
G01X579000Y77000D02*
X585750D01*
G01X577500Y78500D02*
X579000Y77000D01*
G01X577500Y80700D02*
Y78500D01*
G01Y73300D02*
Y70450D01*
G01X587250Y64300D02*
X590600D01*
G01X637250Y126250D02*
X632974D01*
G01X637300Y126300D02*
X637250Y126250D01*
G01X632974D02*
X628000D01*
G01X624069Y126319D02*
X615059D01*
G01X624000Y126250D02*
X624069Y126319D01*
G01X628000Y126250D02*
X624000D01*
G01X615059Y156319D02*
X633716D01*
G01X637300Y132300D02*
Y199060D01*
G01D02*
X621677Y214683D01*
G01X654242Y376350D02*
Y372000D01*
G01Y376350D02*
Y383182D01*
G01D02*
Y389032D01*
G01X687536Y425841D02*
X670390Y408695D01*
G01X668975Y407280D02*
Y402959D01*
G01X670390Y408695D02*
X668975Y407280D01*
G01Y402959D02*
Y396350D01*
G01X583550Y520300D02*
Y516300D01*
G01X579000Y529500D02*
X585750D01*
G01X577500Y531000D02*
X579000Y529500D01*
G01X577500Y533200D02*
Y531000D01*
G01X583550Y523300D02*
Y520300D01*
G01X585650Y525400D02*
X583550Y523300D01*
G01X585750Y525500D02*
X585650Y525400D01*
G01X585750Y529500D02*
Y525500D01*
G01X583550Y512800D02*
Y508800D01*
G01Y504600D02*
Y508800D01*
G01X580060Y525800D02*
Y518960D01*
G01X577500Y525800D02*
Y522950D01*
G01X615059Y609075D02*
X633716D01*
G01X646680Y647138D02*
Y679430D01*
G01Y607180D02*
Y647138D01*
G01X640500Y601000D02*
X646680Y607180D01*
G01X640500Y594500D02*
Y601000D01*
G01X634500Y588750D02*
X634250Y588500D01*
G01X634500Y594500D02*
Y588750D01*
G01X634250Y588500D02*
Y583000D01*
G01X634175Y579075D02*
X615059D01*
G01X634250Y579000D02*
X634175Y579075D01*
G01X634250Y583000D02*
Y579000D01*
G01X659642Y829050D02*
Y824700D01*
G01Y841732D02*
Y835882D01*
G01D02*
Y829050D01*
G01X582648Y829573D02*
Y825223D01*
G01Y842255D02*
Y836405D01*
G01D02*
Y829573D01*
G01X597555Y856859D02*
Y850250D01*
G01X585904Y900960D02*
X594056Y909112D01*
G01X596769Y911825D02*
X594056Y909112D01*
G01X803091Y911825D02*
X596769D01*
G01X598744Y909800D02*
X589904Y900960D01*
G01X802252Y909800D02*
X598744D01*
G01X627308Y903725D02*
X799735D01*
G01X624543Y900960D02*
X627308Y903725D01*
G01X610207Y900960D02*
X624543D01*
G01X601904D02*
X610207D01*
G01X597555Y861180D02*
Y856859D01*
G01X598970Y862595D02*
X597555Y861180D01*
G01X601752Y865376D02*
X598970Y862595D01*
G01X778656Y865376D02*
X601752D01*
G01X600719Y907775D02*
X593904Y900960D01*
G01X801413Y907775D02*
X600719D01*
G01X602694Y905750D02*
X597904Y900960D01*
G01X800574Y905750D02*
X602694D01*
G01X634250Y1036000D02*
Y1041500D01*
G01Y1032000D02*
Y1036000D01*
G01X634500Y1041750D02*
X634250Y1041500D01*
G01X634500Y1047500D02*
Y1041750D01*
G01X634081Y1031831D02*
X615059D01*
G01X634250Y1032000D02*
X634081Y1031831D01*
G01X583050Y975400D02*
Y973400D01*
G01X585750Y978100D02*
X583050Y975400D01*
G01Y973400D02*
Y969500D01*
G01X579000Y982500D02*
X585750D01*
G01X577500Y984000D02*
X579000Y982500D01*
G01X577500Y986200D02*
Y984000D01*
G01X585750Y982500D02*
Y978100D01*
G01X580060Y978800D02*
Y972260D01*
G01X586550Y969500D02*
X590200D01*
G01X577500Y978800D02*
Y975950D01*
G01X615059Y1061831D02*
X633716D01*
G01X650500Y1119500D02*
X748695D01*
G01X640500Y1109500D02*
X650500Y1119500D01*
G01X640500Y1047500D02*
Y1109500D01*
G01X628500Y1464750D02*
Y1468500D01*
G01X581102Y1475204D02*
Y1466929D01*
G01X587380Y1481482D02*
X581102Y1475204D01*
G01X610018Y1481482D02*
X587380D01*
G01X626750Y1464750D02*
X610018Y1481482D01*
G01X628500Y1464750D02*
X626750D01*
G01X692250Y74000D02*
Y78500D01*
G01X690500Y84250D02*
X692250Y82500D01*
G01X690500Y107161D02*
Y84250D01*
G01X692250Y78500D02*
Y82500D01*
G01X698560Y62940D02*
X700300D01*
G01X692250Y69250D02*
X698560Y62940D01*
G01X692250Y74000D02*
Y69250D01*
G01X707937Y57400D02*
X712250D01*
G01X706500D02*
X707937D01*
G01X704200Y59700D02*
X706500Y57400D01*
G01X704200Y64200D02*
Y59700D01*
G01X705500Y65500D02*
X704200Y64200D01*
G01X707700Y65500D02*
X705500D01*
G01X713803Y82500D02*
X712214D01*
G01X717000Y79303D02*
X713803Y82500D01*
G01X717000Y77250D02*
Y79303D01*
G01X707312Y44500D02*
X710000D01*
G01X706762Y45050D02*
X707312Y44500D01*
G01X704750Y45050D02*
X706762D01*
G01X713250Y44500D02*
X710000D01*
G01X714000Y45250D02*
X713250Y44500D01*
G01X714500Y54000D02*
Y51300D01*
G01X715750Y55250D02*
X714500Y54000D01*
G01X715750Y57400D02*
Y55250D01*
G01X714500Y45750D02*
X714000Y45250D01*
G01X714500Y51300D02*
Y45750D01*
G01X715750Y63250D02*
Y57400D01*
G01X710940Y68060D02*
X715750Y63250D01*
G01X707700Y68060D02*
X710940D01*
G01X699600Y40850D02*
X695600D01*
G01X685500Y81500D02*
X687700Y79300D01*
G01X685500Y86000D02*
Y81500D01*
G01X687700Y70936D02*
Y79300D01*
G01X695600Y63036D02*
X687700Y70936D01*
G01X695600Y40850D02*
Y63036D01*
G01X701250Y49750D02*
Y45050D01*
G01X702800Y51300D02*
X701250Y49750D01*
G01X705500Y51300D02*
X702800D01*
G01X701250Y42500D02*
X699600Y40850D01*
G01X701250Y45050D02*
Y42500D01*
G01X704000Y67000D02*
Y73750D01*
G01X702500Y65500D02*
X704000Y67000D01*
G01X700300Y65500D02*
X702500D01*
G01X707937Y73750D02*
X712500D01*
G01D02*
X717000D01*
G01X704000D02*
X707937D01*
G01X729519Y156319D02*
X739272D01*
G01X725500Y152300D02*
X729519Y156319D01*
G01X711600Y152300D02*
X725500D01*
G01X708200Y148900D02*
X711600Y152300D01*
G01X695000Y111661D02*
X690500Y107161D01*
G01X695000Y113500D02*
Y111661D01*
G01X748250Y126500D02*
Y130500D01*
G01X748069Y126319D02*
X739272D01*
G01X748250Y126500D02*
X748069Y126319D01*
G01X748250Y133000D02*
Y130500D01*
G01X748400Y133150D02*
X748250Y133000D01*
G01X748400Y137100D02*
Y133150D01*
G01Y143100D02*
Y215900D01*
G01D02*
X742300Y222000D01*
G01X738032Y458541D02*
X766742Y487251D01*
G01X740417Y466654D02*
X762692Y488929D01*
G01X736256Y425841D02*
X687536D01*
G01X833698Y523283D02*
X736256Y425841D01*
G01X735245Y441434D02*
X776867Y483056D01*
G01X738971Y462344D02*
X764717Y488090D01*
G01X737296Y452077D02*
X770792Y485573D01*
G01X831673Y525060D02*
X737513Y430900D01*
G01X737728Y455373D02*
X768767Y486412D01*
G01X736307Y445360D02*
X774842Y483895D01*
G01X734690Y438015D02*
X826500Y529825D01*
G01X736482Y448399D02*
X772817Y484734D01*
G01X828903Y527234D02*
X736044Y434375D01*
G01X766742Y487251D02*
Y617344D01*
G01X762692Y488929D02*
Y614953D01*
G01X700300Y515100D02*
X698100D01*
G01X704060Y518860D02*
X700300Y515100D01*
G01X704060Y525800D02*
Y518860D01*
G01X694650Y515100D02*
X693500Y516250D01*
G01X698100Y515100D02*
X694650D01*
G01X681000Y518250D02*
X681250Y518000D01*
G01X681000Y522250D02*
Y518250D01*
G01X690000Y517500D02*
X687500D01*
G01X691250Y516250D02*
X690000Y517500D01*
G01X693500Y516250D02*
X691250D01*
G01X681750Y517500D02*
X681250Y518000D01*
G01X687500Y517500D02*
X681750D01*
G01X707800Y520800D02*
Y516950D01*
G01Y523450D02*
Y520800D01*
G01X709650Y525300D02*
X707800Y523450D01*
G01X709650Y529400D02*
X709750Y529500D01*
G01X709650Y525300D02*
Y529400D01*
G01X703000Y529500D02*
X709750D01*
G01X701500Y531000D02*
X703000Y529500D01*
G01X701500Y533200D02*
Y531000D01*
G01X692793Y533200D02*
X690116Y535877D01*
G01X698940Y533200D02*
X692793D01*
G01X688750Y537243D02*
Y543500D01*
G01X690116Y535877D02*
X688750Y537243D01*
G01X695000Y553750D02*
X688750Y547500D01*
G01X695000Y566000D02*
Y553750D01*
G01X688750Y543500D02*
Y547500D01*
G01X764717Y488090D02*
Y615938D01*
G01X686750Y525750D02*
X681000D01*
G01X687500Y526500D02*
X686750Y525750D01*
G01X681250Y534000D02*
Y549000D01*
G01X681000Y533750D02*
X681250Y534000D01*
G01X681000Y532500D02*
Y533750D01*
G01X687000Y558750D02*
X681250Y553000D01*
G01X687000Y564000D02*
Y558750D01*
G01X681250Y549000D02*
Y553000D01*
G01X681000Y525750D02*
Y532500D01*
G01X698300Y519750D02*
X693500D01*
G01X701500Y522950D02*
X698300Y519750D01*
G01X701500Y525800D02*
Y522950D01*
G01X704650Y513450D02*
X703200Y512000D01*
G01X707800Y513450D02*
X704650D01*
G01X702300Y511100D02*
X703200Y512000D01*
G01X698600Y511100D02*
X702300D01*
G01X756975Y627111D02*
Y753924D01*
G01X766742Y617344D02*
X756975Y627111D01*
G01X752925Y624720D02*
Y755602D01*
G01X762692Y614953D02*
X752925Y624720D01*
G01X748175Y579075D02*
X739272D01*
G01X748200Y579050D02*
X748175Y579075D01*
G01X752200Y579050D02*
X748200D01*
G01X757300Y587000D02*
Y582800D01*
G01X756300Y588000D02*
X757300Y587000D01*
G01X752500Y588000D02*
X756300D01*
G01X757300Y580050D02*
Y582800D01*
G01X756300Y579050D02*
X757300Y580050D01*
G01X752200Y579050D02*
X756300D01*
G01X767100Y634101D02*
Y749156D01*
G01X776867Y624334D02*
X767100Y634101D01*
G01X754950Y625705D02*
Y754763D01*
G01X764717Y615938D02*
X754950Y625705D01*
G01X761025Y628961D02*
Y752246D01*
G01X770792Y619194D02*
X761025Y628961D01*
G01X759000Y627981D02*
Y753085D01*
G01X768767Y618214D02*
X759000Y627981D01*
G01X749541Y624913D02*
Y717011D01*
G01X760667Y613787D02*
X749541Y624913D01*
G01X760667Y605500D02*
Y613787D01*
G01X752500Y597333D02*
X760667Y605500D01*
G01X752500Y594000D02*
Y597333D01*
G01X765075Y631713D02*
Y749996D01*
G01X774842Y621946D02*
X765075Y631713D01*
G01X757929Y609075D02*
X739272D01*
G01X763050Y630874D02*
Y751407D01*
G01X772817Y621107D02*
X763050Y630874D01*
G01X756975Y753924D02*
X781993Y778942D01*
G01X752925Y755602D02*
X777943Y780620D01*
G01X767100Y749156D02*
X792118Y774174D01*
G01X754950Y754763D02*
X779968Y779781D01*
G01X761025Y752246D02*
X786043Y777264D01*
G01X759000Y753085D02*
X784018Y778103D01*
G01X749541Y755082D02*
X775918Y781459D01*
G01X749541Y717011D02*
Y755082D01*
G01X765075Y749996D02*
X790093Y775014D01*
G01X763050Y751407D02*
X788068Y776425D01*
G01X674375Y859980D02*
Y855659D01*
G01D02*
Y849050D01*
G01X740364Y901060D02*
X856360D01*
G01X733901D02*
X733895Y901054D01*
G01X740364Y901060D02*
X733901D01*
G01X677746Y863351D02*
X675790Y861395D01*
G01X780851Y863351D02*
X677746D01*
G01X675790Y861395D02*
X674375Y859980D01*
G01X769554Y936275D02*
X758562Y925283D01*
G01D02*
X755389Y922110D01*
G01X776987Y932225D02*
X762537Y917775D01*
G01X712863Y915240D02*
X712760Y915137D01*
G01X765218Y915240D02*
X712863D01*
G01X769130Y919152D02*
X765218Y915240D01*
G01X768449Y929466D02*
X759068Y920085D01*
G01X714400Y969600D02*
X710950D01*
G01X758250Y1043000D02*
Y1047750D01*
G01X749381Y1031831D02*
X749550Y1032000D01*
G01X739272Y1031831D02*
X749381D01*
G01X749650Y1032100D02*
X749550Y1032000D01*
G01X749650Y1036000D02*
Y1032100D01*
G01X758250Y1040113D02*
Y1043000D01*
G01X757500Y1039363D02*
X758250Y1040113D01*
G01X750500Y1039363D02*
X757500D01*
G01X749650Y1038513D02*
X750500Y1039363D01*
G01X749650Y1036000D02*
Y1038513D01*
G01X686750Y978750D02*
X681000D01*
G01X687500Y979500D02*
X686750Y978750D01*
G01X681250Y987000D02*
Y1002000D01*
G01X681000Y986750D02*
X681250Y987000D01*
G01X681000Y985500D02*
Y986750D01*
G01X687000Y1011750D02*
X681250Y1006000D01*
G01X687000Y1017000D02*
Y1011750D01*
G01X681250Y1002000D02*
Y1006000D01*
G01X681000Y978750D02*
Y985500D01*
G01X694450Y968300D02*
X698000D01*
G01X693500Y969250D02*
X694450Y968300D01*
G01X700700D02*
X698000D01*
G01X704060Y971660D02*
X700700Y968300D01*
G01X704060Y978800D02*
Y971660D01*
G01X681000Y971250D02*
X681250Y971000D01*
G01X681000Y975250D02*
Y971250D01*
G01X690000Y970500D02*
X687500D01*
G01X691250Y969250D02*
X690000Y970500D01*
G01X693500Y969250D02*
X691250D01*
G01X681750Y970500D02*
X681250Y971000D01*
G01X687500Y970500D02*
X681750D01*
G01X693151Y986200D02*
X690141Y989210D01*
G01X698940Y986200D02*
X693151D01*
G01X688750Y990601D02*
X690141Y989210D01*
G01X688750Y996500D02*
Y990601D01*
G01Y1006750D02*
Y1000500D01*
G01X695000Y1013000D02*
X688750Y1006750D01*
G01X695000Y1019000D02*
Y1013000D01*
G01X688750Y1000500D02*
Y996500D01*
G01X707450Y973600D02*
Y969600D01*
G01X709850Y982400D02*
Y978300D01*
G01X709750Y982500D02*
X709850Y982400D01*
G01X707450Y975900D02*
Y973600D01*
G01X709850Y978300D02*
X707450Y975900D01*
G01X703000Y982500D02*
X709750D01*
G01X701500Y984000D02*
X703000Y982500D01*
G01X701500Y986200D02*
Y984000D01*
G01X698300Y972750D02*
X693500D01*
G01X701500Y975950D02*
X698300Y972750D01*
G01X701500Y978800D02*
Y975950D01*
G01X755669Y1121525D02*
X802162Y1075032D01*
G01X757500Y1048500D02*
X752500D01*
G01X758250Y1047750D02*
X757500Y1048500D01*
G01X761364Y1135000D02*
X759762D01*
G01X778001Y1151637D02*
X761364Y1135000D01*
G01X764039Y1125576D02*
X814330Y1075285D01*
G01X762100Y1138600D02*
X759700D01*
G01X777162Y1153662D02*
X762100Y1138600D01*
G01X761248Y1123550D02*
X811162Y1073636D01*
G01X752500Y1054500D02*
X784291D01*
G01X739272Y1061831D02*
X757929D01*
G01X748695Y1119500D02*
X771236Y1096959D01*
G01X833698Y589769D02*
Y523283D01*
G01X776867Y483056D02*
Y624334D01*
G01X770792Y485573D02*
Y619194D01*
G01X831673Y588930D02*
Y525060D01*
G01X768767Y486412D02*
Y618214D01*
G01X774842Y483895D02*
Y621946D01*
G01X826500Y529825D02*
Y588375D01*
G01X772817Y484734D02*
Y621107D01*
G01X828903Y588836D02*
Y527234D01*
G01X855752Y626268D02*
X863430Y618590D01*
G01X855752Y649625D02*
Y626268D01*
G01X852900Y652477D02*
X855752Y649625D01*
G01X852900Y667720D02*
Y652477D01*
G01X800684Y647754D02*
Y652390D01*
G01X809670Y638768D02*
X800684Y647754D01*
G01X812068Y638768D02*
X809670D01*
G01X899900Y550936D02*
X812068Y638768D01*
G01X800684Y655927D02*
Y652390D01*
G01X812082Y667325D02*
X800684Y655927D01*
G01X830762Y662910D02*
X826347Y667325D01*
G01X837390Y662910D02*
X830762D01*
G01X775200Y648267D02*
X833698Y589769D01*
G01X775200Y745800D02*
Y648267D01*
G01X859590Y650110D02*
X863033D01*
G01X810810Y640793D02*
X805128Y646475D01*
G01X812907Y640793D02*
X810810D01*
G01X902589Y551111D02*
X812907Y640793D01*
G01X805128Y657251D02*
Y646475D01*
G01X813177Y665300D02*
X805128Y657251D01*
G01X825508Y665300D02*
X813177D01*
G01X830458Y660350D02*
X825508Y665300D01*
G01X837390Y660350D02*
X830458D01*
G01X837390Y657790D02*
X829490D01*
G01X826990Y659190D02*
X824740D01*
G01X828390Y657790D02*
X826990Y659190D01*
G01X829490Y657790D02*
X828390D01*
G01X824740Y659190D02*
Y655190D01*
G01X853727Y617248D02*
X909075Y561900D01*
G01X853727Y648786D02*
Y617248D01*
G01X851356Y651157D02*
X853727Y648786D01*
G01X851355Y651157D02*
X851356D01*
G01X850875Y651637D02*
X851355Y651157D01*
G01X850875Y666045D02*
Y651637D01*
G01X773175Y647428D02*
X831673Y588930D01*
G01X773175Y746639D02*
Y647428D01*
G01X859590Y665470D02*
X880666D01*
G01X796484Y648122D02*
Y648490D01*
G01X808769Y635837D02*
X796484Y648122D01*
G01X808769Y635836D02*
Y635837D01*
G01X812136Y635836D02*
X808769D01*
G01X897600Y550372D02*
X812136Y635836D01*
G01X796484Y654786D02*
Y648490D01*
G01X811049Y669351D02*
X796484Y654786D01*
G01X831066Y665470D02*
X827185Y669351D01*
G01X837390Y665470D02*
X831066D01*
G01X800514Y661782D02*
X810132Y671400D01*
G01X792598Y661782D02*
X800514D01*
G01X788160Y666220D02*
X792598Y661782D01*
G01X849677Y607737D02*
X905040Y552374D01*
G01X849677Y647107D02*
Y607737D01*
G01X846825Y649959D02*
X849677Y647107D01*
G01X846825Y663375D02*
Y649959D01*
G01X842170Y668030D02*
X846825Y663375D01*
G01X859590Y652670D02*
X863709D01*
G01X848850Y664830D02*
X843090Y670590D01*
G01X848850Y650798D02*
Y664830D01*
G01X850516Y649132D02*
X848850Y650798D01*
G01X850517Y649132D02*
X850516D01*
G01X851702Y647947D02*
X850517Y649132D01*
G01X851702Y611035D02*
Y647947D01*
G01X907065Y555672D02*
X851702Y611035D01*
G01X859590Y662910D02*
X880362D01*
G01X859590Y657790D02*
X873325D01*
G01X821208Y623900D02*
X894530Y550578D01*
G01X817841Y623900D02*
X821208D01*
G01X816068Y625673D02*
X817841Y623900D01*
G01X785375Y656366D02*
Y681275D01*
G01X816068Y625673D02*
X785375Y656366D01*
G01X769125Y645750D02*
Y748317D01*
G01X826500Y588375D02*
X769125Y645750D01*
G01X865530Y655230D02*
X859590D01*
G01Y660350D02*
X880058D01*
G01X771150Y646589D02*
X828903Y588836D01*
G01X771150Y747478D02*
Y646589D01*
G01X811245Y684635D02*
X816104Y679776D01*
G01X793014Y684635D02*
X811245D01*
G01X789442Y681063D02*
X793014Y684635D01*
G01X832282Y675710D02*
X837390D01*
G01X830516Y677476D02*
X832282Y675710D01*
G01X818404Y677476D02*
X830516D01*
G01X816104Y679776D02*
X818404Y677476D01*
G01X844910Y675710D02*
X852900Y667720D01*
G01X837390Y675710D02*
X844910D01*
G01X817373Y729519D02*
Y744099D01*
G01X879042Y667850D02*
X817373Y729519D01*
G01Y753986D02*
Y744099D01*
G01X823667Y760280D02*
X817373Y753986D01*
G01X833200Y760280D02*
X823667D01*
G01X818991Y667325D02*
X812082D01*
G01X818992Y667326D02*
X818991Y667325D01*
G01X820668Y667326D02*
X818992D01*
G01X820669Y667325D02*
X820668Y667326D01*
G01X826347Y667325D02*
X820669D01*
G01X788909Y759509D02*
X775200Y745800D01*
G01X816402Y759509D02*
X788909D01*
G01X819530Y762637D02*
X816402Y759509D01*
G01X862000Y760000D02*
X862500D01*
G01X859500Y762500D02*
X862000Y760000D01*
G01X862500D02*
X866050D01*
G01X825312Y742195D02*
X936783Y630724D01*
G01X825312Y748840D02*
Y742195D01*
G01X829072Y752600D02*
X825312Y748840D01*
G01X833200Y752600D02*
X829072D01*
G01X802390Y676210D02*
X796200Y682400D01*
G01X806535Y676210D02*
X802390D01*
G01X831978Y673150D02*
X837390D01*
G01X829677Y675451D02*
X831978Y673150D01*
G01X814585Y675451D02*
X829677D01*
G01X813826Y676210D02*
X814585Y675451D01*
G01X806535Y676210D02*
X813826D01*
G01X843770Y673150D02*
X850875Y666045D01*
G01X837390Y673150D02*
X843770D01*
G01X788070Y761534D02*
X773175Y746639D01*
G01X828464Y757720D02*
X833200D01*
G01X821262Y750518D02*
X828464Y757720D01*
G01X821262Y742195D02*
Y750518D01*
G01X821261Y742194D02*
X821262Y742195D01*
G01X821261Y740518D02*
Y742194D01*
G01X932733Y629046D02*
X821261Y740518D01*
G01X829362Y743873D02*
X940833Y632402D01*
G01X829362Y747162D02*
Y743873D01*
G01X829680Y747480D02*
X829362Y747162D01*
G01X833200Y747480D02*
X829680D01*
G01X827185Y669351D02*
X811049D01*
G01X831370Y668030D02*
X837390D01*
G01X828000Y671400D02*
X831370Y668030D01*
G01X810132Y671400D02*
X828000D01*
G01X837390Y668030D02*
X842170D01*
G01X843090Y670590D02*
X837390D01*
G01X796587Y673425D02*
X791243Y668081D01*
G01X828839Y673425D02*
X796587D01*
G01X831674Y670590D02*
X828839Y673425D01*
G01X837390Y670590D02*
X831674D01*
G01X827337Y743034D02*
X938808Y631563D01*
G01X827337Y748001D02*
Y743034D01*
G01X829376Y750040D02*
X827337Y748001D01*
G01X833200Y750040D02*
X829376D01*
G01X832586Y678270D02*
X837390D01*
G01X831355Y679501D02*
X832586Y678270D01*
G01X822899Y679501D02*
X831355D01*
G01X815740Y686660D02*
X822899Y679501D01*
G01X790760Y686660D02*
X815740D01*
G01X785375Y681275D02*
X790760Y686660D01*
G01X837709Y678589D02*
Y681095D01*
G01X837390Y678270D02*
X837709Y678589D01*
G01X769125Y748317D02*
X794143Y773335D01*
G01X823287Y741356D02*
X934758Y629885D01*
G01X823287Y749679D02*
Y741356D01*
G01X828768Y755160D02*
X823287Y749679D01*
G01X833200Y755160D02*
X828768D01*
G01X796168Y772496D02*
X771150Y747478D01*
G01X846870Y854539D02*
Y865991D01*
G01X839231Y846900D02*
X846870Y854539D01*
G01X796086Y846900D02*
X839231D01*
G01X781993Y832807D02*
X796086Y846900D01*
G01X781993Y778942D02*
Y832807D01*
G01X855598Y827840D02*
X861100D01*
G01X853212Y825454D02*
X855598Y827840D01*
G01X853212Y800623D02*
Y825454D01*
G01X865051Y788784D02*
X853212Y800623D01*
G01X842820Y856455D02*
Y869183D01*
G01X839491Y853126D02*
X842820Y856455D01*
G01X796584Y853126D02*
X839491D01*
G01X777943Y834485D02*
X796584Y853126D01*
G01X777943Y780620D02*
Y834485D01*
G01X861100Y817600D02*
X868742D01*
G01X826600Y769000D02*
X824000D01*
G01X827640Y767960D02*
X826600Y769000D01*
G01X833200Y767960D02*
X827640D01*
G01X821000Y767500D02*
X818050D01*
G01X822500Y769000D02*
X821000Y767500D01*
G01X824000Y769000D02*
X822500D01*
G01X818050Y767500D02*
Y772000D01*
G01X819500Y785500D02*
X824500Y780500D01*
G01X817950Y785500D02*
X819500D01*
G01X828297Y776703D02*
X824500Y780500D01*
G01X828297Y774231D02*
Y776703D01*
G01X829448Y773080D02*
X828297Y774231D01*
G01X833200Y773080D02*
X829448D01*
G01X828766Y762637D02*
X819530D01*
G01X828969Y762840D02*
X828766Y762637D01*
G01X833200Y762840D02*
X828969D01*
G01X859500Y763800D02*
Y762500D01*
G01X857900Y765400D02*
X859500Y763800D01*
G01X855400Y765400D02*
X857900D01*
G01X830302Y830400D02*
X838900D01*
G01X828687Y832015D02*
X830302Y830400D01*
G01X795521Y832015D02*
X828687D01*
G01X792118Y828612D02*
X795521Y832015D01*
G01X792118Y774174D02*
Y828612D01*
G01X857262Y802301D02*
X866662Y792901D01*
G01X857262Y822262D02*
Y802301D01*
G01X857720Y822720D02*
X857262Y822262D01*
G01X861100Y822720D02*
X857720D01*
G01X844845Y855616D02*
Y867587D01*
G01X840329Y851100D02*
X844845Y855616D01*
G01X797422Y851100D02*
X840329D01*
G01X779968Y833646D02*
X797422Y851100D01*
G01X779968Y779781D02*
Y833646D01*
G01X831214Y838080D02*
X838900D01*
G01X831204Y838090D02*
X831214Y838080D01*
G01X793004Y838090D02*
X831204D01*
G01X786043Y831129D02*
X793004Y838090D01*
G01X786043Y777264D02*
Y831129D01*
G01X828980Y770520D02*
X824500Y775000D01*
G01X833200Y770520D02*
X828980D01*
G01X823000Y776500D02*
X818050D01*
G01X824500Y775000D02*
X823000Y776500D01*
G01X818050D02*
Y781000D01*
G01X815563Y761534D02*
X788070D01*
G01X818691Y764662D02*
X815563Y761534D01*
G01X827927Y764662D02*
X818691D01*
G01X828665Y765400D02*
X827927Y764662D01*
G01X833200Y765400D02*
X828665D01*
G01X848895Y853700D02*
Y864395D01*
G01X840070Y844875D02*
X848895Y853700D01*
G01X796925Y844875D02*
X840070D01*
G01X784018Y831968D02*
X796925Y844875D01*
G01X784018Y778103D02*
Y831968D01*
G01X852415Y835520D02*
X861100D01*
G01X847137Y830242D02*
X852415Y835520D01*
G01X847137Y798106D02*
Y830242D01*
G01X862723Y782520D02*
X847137Y798106D01*
G01X873962Y782520D02*
X862723D01*
G01X838900Y817600D02*
X831000D01*
G01X827382Y819000D02*
X826250D01*
G01X828782Y817600D02*
X827382Y819000D01*
G01X831000Y817600D02*
X828782D01*
G01X826250Y819000D02*
Y815000D01*
G01X775918Y837071D02*
X778735Y839888D01*
G01X775918Y781459D02*
Y837071D01*
G01X861100Y820160D02*
X867299D01*
G01X854537Y830400D02*
X861100D01*
G01X851187Y827050D02*
X854537Y830400D01*
G01X851187Y799784D02*
Y827050D01*
G01X864213Y786758D02*
X851187Y799784D01*
G01X867040Y815040D02*
X861100D01*
G01X860600Y853984D02*
X882447Y832137D01*
G01X860600Y856920D02*
Y853984D01*
G01X861100Y812480D02*
X863520D01*
G01X830606Y832960D02*
X838900D01*
G01X829526Y834040D02*
X830606Y832960D01*
G01X794682Y834040D02*
X829526D01*
G01X790093Y829451D02*
X794682Y834040D01*
G01X790093Y775014D02*
Y829451D01*
G01X863241Y803050D02*
X861986Y804305D01*
G01X861100Y805191D02*
X861986Y804305D01*
G01X861100Y809920D02*
Y805191D01*
G01X857172Y843325D02*
X865230D01*
G01X852946Y847551D02*
X857172Y843325D01*
G01X852946Y860718D02*
Y847551D01*
G01X855237Y801462D02*
X865823Y790876D01*
G01X855237Y823858D02*
Y801462D01*
G01X856659Y825280D02*
X855237Y823858D01*
G01X861100Y825280D02*
X856659D01*
G01X829998Y827840D02*
X838900D01*
G01X827848Y829990D02*
X829998Y827840D01*
G01X796360Y829990D02*
X827848D01*
G01X794143Y827773D02*
X796360Y829990D01*
G01X794143Y773335D02*
Y827773D01*
G01X849162Y798945D02*
X863562Y784545D01*
G01X849162Y828646D02*
Y798945D01*
G01X853476Y832960D02*
X849162Y828646D01*
G01X861100Y832960D02*
X853476D01*
G01X855400Y841300D02*
X864391D01*
G01X850921Y845779D02*
X855400Y841300D01*
G01X850921Y858132D02*
Y845779D01*
G01X801100Y770700D02*
X795300Y764900D01*
G01X801100Y817100D02*
Y770700D01*
G01X806362Y822362D02*
X801100Y817100D01*
G01X826884Y822362D02*
X806362D01*
G01X829086Y820160D02*
X826884Y822362D01*
G01X838900Y820160D02*
X829086D01*
G01X854971Y856448D02*
X880209Y831210D01*
G01X854971Y858481D02*
Y856448D01*
G01X799075Y772075D02*
X791500Y764500D01*
G01X799075Y817939D02*
Y772075D01*
G01X805523Y824387D02*
X799075Y817939D01*
G01X827723Y824387D02*
X805523D01*
G01X829390Y822720D02*
X827723Y824387D01*
G01X838900Y822720D02*
X829390D01*
G01X830910Y835520D02*
X838900D01*
G01X830365Y836065D02*
X830910Y835520D01*
G01X793843Y836065D02*
X830365D01*
G01X788068Y830290D02*
X793843Y836065D01*
G01X788068Y776425D02*
Y830290D01*
G01X796168Y826934D02*
Y772496D01*
G01X797199Y827965D02*
X796168Y826934D01*
G01X827009Y827965D02*
X797199D01*
G01X829694Y825280D02*
X827009Y827965D01*
G01X838900Y825280D02*
X829694D01*
G01X853907Y869720D02*
X860600D01*
G01X853396Y869209D02*
X853907Y869720D01*
G01X850088Y869209D02*
X853396D01*
G01X846870Y865991D02*
X850088Y869209D01*
G01X854705Y874840D02*
X860600D01*
G01X854235Y875310D02*
X854705Y874840D01*
G01X848947Y875310D02*
X854235D01*
G01X842820Y869183D02*
X848947Y875310D01*
G01X801950Y947652D02*
X806713Y952415D01*
G01X801950Y940330D02*
Y947652D01*
G01X856360Y901060D02*
X867500Y912200D01*
G01X782509Y872280D02*
X777426Y877363D01*
G01X838400Y872280D02*
X782509D01*
G01X832000Y886595D02*
Y887000D01*
G01X836075Y882520D02*
X832000Y886595D01*
G01X838400Y882520D02*
X836075D01*
G01X830500Y888500D02*
X827750D01*
G01X832000Y887000D02*
X830500Y888500D01*
G01X827750D02*
Y893000D01*
G01X782100Y864600D02*
X780851Y863351D01*
G01X838400Y864600D02*
X782100D01*
G01X803621Y911295D02*
X803091Y911825D01*
G01X811171Y911295D02*
X803621D01*
G01X811172Y911296D02*
X811171Y911295D01*
G01X832468Y911296D02*
X811172D01*
G01X844282Y923110D02*
X832468Y911296D01*
G01X897495Y923110D02*
X844282D01*
G01X854401Y872280D02*
X860600D01*
G01X853396Y873285D02*
X854401Y872280D01*
G01X850543Y873285D02*
X853396D01*
G01X844845Y867587D02*
X850543Y873285D01*
G01X860600Y877400D02*
X863200D01*
G01X802782Y909270D02*
X802252Y909800D01*
G01X812010Y909270D02*
X802782D01*
G01X812011Y909271D02*
X812010Y909270D01*
G01X838510Y909271D02*
X812011D01*
G01X844940Y915701D02*
X838510Y909271D01*
G01X850324Y921085D02*
X844940Y915701D01*
G01X895899Y921085D02*
X850324D01*
G01X807900Y936275D02*
X769554D01*
G01X809629Y938004D02*
X807900Y936275D01*
G01X809629Y940331D02*
Y938004D01*
G01X809630Y940330D02*
X809629Y940331D01*
G01X809905Y948365D02*
X892322D01*
G01X807070Y945530D02*
X809905Y948365D01*
G01X807070Y940330D02*
Y945530D01*
G01X799390Y948713D02*
X805117Y954440D01*
G01X799390Y940330D02*
Y948713D01*
G01X851660Y867160D02*
X860600D01*
G01X848895Y864395D02*
X851660Y867160D01*
G01X782205Y869720D02*
X776587Y875338D01*
G01X838400Y869720D02*
X782205D01*
G01X854995Y903195D02*
X866410Y914610D01*
G01X800265Y903195D02*
X854995D01*
G01X799735Y903725D02*
X800265Y903195D01*
G01X798818Y876662D02*
X796396Y879084D01*
G01X825427Y876662D02*
X798818D01*
G01X826165Y877400D02*
X825427Y876662D01*
G01X838400Y877400D02*
X826165D01*
G01X796396Y879084D02*
X794067Y881413D01*
G01X780440Y867160D02*
X778656Y865376D01*
G01X838400Y867160D02*
X780440D01*
G01X828080Y859480D02*
X826000Y857400D01*
G01X838400Y859480D02*
X828080D01*
G01X801943Y907245D02*
X801413Y907775D01*
G01X846385Y907245D02*
X801943D01*
G01X853398Y914258D02*
X846385Y907245D01*
G01X858200Y919060D02*
X853398Y914258D01*
G01X894303Y919060D02*
X858200D01*
G01X854268Y862040D02*
X852946Y860718D01*
G01X860600Y862040D02*
X854268D01*
G01X838400D02*
X825900D01*
G01X811765Y932225D02*
X776987D01*
G01X814750Y935210D02*
X811765Y932225D01*
G01X814750Y940330D02*
Y935210D01*
G01X838400Y890600D02*
X833500Y895500D01*
G01X838400Y885080D02*
Y890600D01*
G01X831500Y897500D02*
X833500Y895500D01*
G01X827750Y897500D02*
X831500D01*
G01X833540Y879960D02*
X832000Y881500D01*
G01X838400Y879960D02*
X833540D01*
G01X828166Y880785D02*
X827637Y880256D01*
G01X829889Y880785D02*
X828166D01*
G01X830604Y881500D02*
X829889Y880785D01*
G01X832000Y881500D02*
X830604D01*
G01X827637Y880256D02*
Y884453D01*
G01X787472Y874637D02*
X785560Y876549D01*
G01X826266Y874637D02*
X787472D01*
G01X826469Y874840D02*
X826266Y874637D01*
G01X838400Y874840D02*
X826469D01*
G01X785560Y876549D02*
X782721Y879388D01*
G01X780178Y930200D02*
X769130Y919152D01*
G01X812740Y930200D02*
X780178D01*
G01X817310Y934770D02*
X812740Y930200D01*
G01X817310Y940330D02*
Y934770D01*
G01X819870Y940330D02*
Y932430D01*
G01X822470Y927680D02*
X818470D01*
G01X819870Y931330D02*
Y932430D01*
G01X818470Y929930D02*
X819870Y931330D01*
G01X818470Y927680D02*
Y929930D01*
G01X850920Y858133D02*
X850921Y858132D01*
G01X850920Y863000D02*
Y858133D01*
G01X852520Y864600D02*
X850920Y863000D01*
G01X860600Y864600D02*
X852520D01*
G01X773233Y934250D02*
X768449Y929466D01*
G01X810790Y934250D02*
X773233D01*
G01X812190Y935650D02*
X810790Y934250D01*
G01X812190Y940330D02*
Y935650D01*
G01X855970Y859480D02*
X854971Y858481D01*
G01X860600Y859480D02*
X855970D01*
G01X808309Y950390D02*
X891483D01*
G01X804510Y946591D02*
X808309Y950390D01*
G01X804510Y940330D02*
Y946591D01*
G01X864653Y916728D02*
X860219Y912294D01*
G01X801104Y905220D02*
X800574Y905750D01*
G01X853145Y905220D02*
X801104D01*
G01X860219Y912294D02*
X853145Y905220D01*
G01X817753Y978382D02*
Y1078073D01*
G01X819870Y976265D02*
X817753Y978382D01*
G01X819870Y962530D02*
Y976265D01*
G01X806713Y952415D02*
X890644D01*
G01X808500Y975156D02*
Y1068694D01*
G01X812190Y971466D02*
X808500Y975156D01*
G01X812190Y962530D02*
Y971466D01*
G01X804490Y956667D02*
X889168D01*
G01X801950Y959207D02*
X804490Y956667D01*
G01X801950Y962530D02*
Y959207D01*
G01X848320Y974180D02*
X848400Y974100D01*
G01X844120Y974180D02*
X848320D01*
G01X844120D02*
X839970D01*
G01D02*
Y969920D01*
G01X805117Y954440D02*
X889805D01*
G01X822430Y962530D02*
Y968470D01*
G01Y974140D02*
X822470Y974180D01*
G01X822430Y968470D02*
Y974140D01*
G01X822470Y974180D02*
X826470D01*
G01X828772Y968732D02*
X830470Y970430D01*
G01X827233Y968732D02*
X828772D01*
G01X824990Y966489D02*
X827233Y968732D01*
G01X824990Y962530D02*
Y966489D01*
G01X830470Y970430D02*
Y974180D01*
G01D02*
X834470D01*
G01X805329Y958692D02*
X888329D01*
G01X804510Y959511D02*
X805329Y958692D01*
G01X804510Y962530D02*
Y959511D01*
G01X814330Y1075285D02*
Y1026361D01*
G01Y977058D02*
Y1026361D01*
G01X817310Y974078D02*
X814330Y977058D01*
G01X817310Y962530D02*
Y974078D01*
G01X811162Y1028971D02*
X810751Y1028560D01*
G01X811162Y1073636D02*
Y1028971D01*
G01Y1028149D02*
X810751Y1028560D01*
G01X811162Y976677D02*
Y1028149D01*
G01X814750Y973089D02*
X811162Y976677D01*
G01X814750Y962530D02*
Y973089D01*
G01X802289Y1036502D02*
X797473Y1041318D01*
G01X802289Y972749D02*
Y1036502D01*
G01X807070Y967968D02*
X802289Y972749D01*
G01X807070Y962530D02*
Y967968D01*
G01X784291Y1054500D02*
X797473Y1041318D01*
G01X839684Y966706D02*
X834871D01*
G01X839970Y966420D02*
X839684Y966706D01*
G01X828725D02*
X834871D01*
G01X827550Y965531D02*
X828725Y966706D01*
G01X827550Y962530D02*
Y965531D01*
G01X805712Y973761D02*
Y1062483D01*
G01X809630Y969843D02*
X805712Y973761D01*
G01X809630Y962530D02*
Y969843D01*
G01X817753Y1078073D02*
X779222Y1116604D01*
G01X768086Y1127740D02*
X779222Y1116604D01*
G01X808500Y1068694D02*
X802162Y1075032D01*
G01X805712Y1062483D02*
X771236Y1096959D01*
G01X788615Y1151637D02*
X778001D01*
G01X793315Y1156337D02*
X788615Y1151637D01*
G01X961878Y1156337D02*
X793315D01*
G01X787776Y1153662D02*
X777162D01*
G01X792476Y1158362D02*
X787776Y1153662D01*
G01X959876Y1158362D02*
X792476D01*
G01X912832Y268110D02*
X989899Y345222D01*
G01X911811Y268110D02*
X912832D01*
G01X904877Y282677D02*
X909315Y287115D01*
G01X904725Y282677D02*
X904877D01*
G01X911811Y263779D02*
X991924Y343892D01*
G01X907240Y315489D02*
X1014979Y423228D01*
G01X907240Y288940D02*
Y315489D01*
G01X905308Y287008D02*
X907240Y288940D01*
G01X904725Y287008D02*
X905308D01*
G01X899900Y350215D02*
Y550936D01*
G01X902184Y347931D02*
X899900Y350215D01*
G01X902184Y347219D02*
Y347931D01*
G01X902589Y356649D02*
Y551111D01*
G01X906616Y352622D02*
X902589Y356649D01*
G01X906616Y351586D02*
Y352622D01*
G01X907834Y324675D02*
X1014573Y431414D01*
G01X903809Y324675D02*
X907834D01*
G01X895890Y316756D02*
X903809Y324675D01*
G01X895890Y312973D02*
Y316756D01*
G01X895127Y312210D02*
X895890Y312973D01*
G01X895127Y303873D02*
Y312210D01*
G01X897638Y301362D02*
X895127Y303873D01*
G01X897638Y300787D02*
Y301362D01*
G01X910360Y363520D02*
X910330Y363490D01*
G01X910360Y369010D02*
Y363520D01*
G01X909090Y370280D02*
X910360Y369010D01*
G01X909090Y556511D02*
Y370280D01*
G01X950843Y378437D02*
X1002209Y429803D01*
G01X950843Y378827D02*
Y378437D01*
G01X897600Y345655D02*
Y550372D01*
G01X898059Y345196D02*
X897600Y345655D01*
G01X898059Y343029D02*
Y345196D01*
G01X909423Y355524D02*
Y354393D01*
G01X905040Y359907D02*
X909423Y355524D01*
G01X905040Y552374D02*
Y359907D01*
G01X909315Y314458D02*
X1015257Y420400D01*
G01X909315Y287115D02*
Y314458D01*
G01X907065Y361705D02*
Y555672D01*
G01X908340Y360430D02*
X907065Y361705D01*
G01X908452Y322429D02*
X1015412Y429389D01*
G01X904427Y322429D02*
X908452D01*
G01X900142Y318144D02*
X904427Y322429D01*
G01X900142Y299382D02*
Y318144D01*
G01X897638Y296878D02*
X900142Y299382D01*
G01X897638Y296457D02*
Y296878D01*
G01X894530Y342889D02*
X882823Y331182D01*
G01X894530Y550578D02*
Y342889D01*
G01X908869Y319982D02*
X1015018Y426131D01*
G01X904844Y319982D02*
X908869D01*
G01X902218Y317356D02*
X904844Y319982D01*
G01X902218Y304282D02*
Y317356D01*
G01X904725Y301775D02*
X902218Y304282D01*
G01X904725Y301181D02*
Y301775D01*
G01X909075Y556526D02*
X909090Y556511D01*
G01X909075Y561900D02*
Y556526D01*
G01X946751Y530020D02*
X951739D01*
G01X945838Y529107D02*
X946751Y530020D01*
G01X954680D02*
X951739D01*
G01X957403Y527297D02*
X954680Y530020D01*
G01X959913Y527297D02*
X957403D01*
G01X946123Y556600D02*
X951915D01*
G01X956700D02*
X951915D01*
G01X959889Y553411D02*
X956700Y556600D01*
G01X945788Y640501D02*
X883914Y702375D01*
G01X950820Y640501D02*
X945788D01*
G01X950821Y640502D02*
X950820Y640501D01*
G01X1194059Y640502D02*
X950821D01*
G01X933540Y615655D02*
X881345Y667850D01*
G01X1182831Y615655D02*
X933540D01*
G01X955855Y628352D02*
X1189025D01*
G01X955854Y628351D02*
X955855Y628352D01*
G01X940754Y628351D02*
X955854D01*
G01X940753Y628352D02*
X940754Y628351D01*
G01X939154Y628352D02*
X940753D01*
G01X936783Y630723D02*
X939154Y628352D01*
G01X936783Y630724D02*
Y630723D01*
G01X865945Y647198D02*
Y643688D01*
G01X863033Y650110D02*
X865945Y647198D01*
G01Y641118D02*
Y643688D01*
G01X867873Y639190D02*
X865945Y641118D01*
G01X871240Y639190D02*
X867873D01*
G01X949143Y644552D02*
X1196757D01*
G01X949142Y644551D02*
X949143Y644552D01*
G01X947466Y644551D02*
X949142D01*
G01X888075Y703942D02*
X947466Y644551D01*
G01X870200Y634650D02*
Y631500D01*
G01X871240Y635690D02*
X870200Y634650D01*
G01X932965Y613171D02*
X1178851D01*
G01X880666Y665470D02*
X932965Y613171D01*
G01X932733Y629045D02*
Y629046D01*
G01X937476Y624302D02*
X932733Y629045D01*
G01X939075Y624302D02*
X937476D01*
G01X939076Y624301D02*
X939075Y624302D01*
G01X957532Y624301D02*
X939076D01*
G01X957533Y624302D02*
X957532Y624301D01*
G01X1185667Y624302D02*
X957533D01*
G01X954177Y632402D02*
X1190703D01*
G01X954176Y632401D02*
X954177Y632402D01*
G01X942432Y632401D02*
X954176D01*
G01X942431Y632402D02*
X942432Y632401D01*
G01X940833Y632402D02*
X942431D01*
G01X943271Y634426D02*
X877575Y700122D01*
G01X953337Y634426D02*
X943271D01*
G01X953338Y634427D02*
X953337Y634426D01*
G01X1191542Y634427D02*
X953338D01*
G01X863709Y652670D02*
X866276Y650103D01*
G01X869189Y647190D02*
X871240D01*
G01X866276Y650103D02*
X869189Y647190D01*
G01X871240D02*
Y643190D01*
G01X944949Y638476D02*
X881889Y701536D01*
G01X951659Y638476D02*
X944949D01*
G01X951660Y638477D02*
X951659Y638476D01*
G01X1193220Y638477D02*
X951660D01*
G01X950821Y652652D02*
X1247880D01*
G01X896401Y707072D02*
X950821Y652652D01*
G01X951660Y654677D02*
X1247041D01*
G01X898426Y707911D02*
X951660Y654677D01*
G01X933176Y610096D02*
X1175335D01*
G01X880362Y662910D02*
X933176Y610096D01*
G01X949143Y648602D02*
X1251254D01*
G01X892351Y705394D02*
X949143Y648602D01*
G01X955016Y630377D02*
X1189864D01*
G01X955015Y630376D02*
X955016Y630377D01*
G01X941593Y630376D02*
X955015D01*
G01X941592Y630377D02*
X941593Y630376D01*
G01X939993Y630377D02*
X941592D01*
G01X938808Y631562D02*
X939993Y630377D01*
G01X938808Y631563D02*
Y631562D01*
G01X952499Y656702D02*
X1235102D01*
G01X900451Y708750D02*
X952499Y656702D01*
G01X932992Y604552D02*
X1164529D01*
G01X879516Y658028D02*
X932992Y604552D01*
G01X873563Y658028D02*
X879516D01*
G01X873325Y657790D02*
X873563Y658028D01*
G01X949982Y642527D02*
X1194898D01*
G01X949981Y642526D02*
X949982Y642527D01*
G01X946627Y642526D02*
X949981D01*
G01X885940Y703213D02*
X946627Y642526D01*
G01X952499Y636452D02*
X1192381D01*
G01X952498Y636451D02*
X952499Y636452D01*
G01X944110Y636451D02*
X952498D01*
G01X879601Y700960D02*
X944110Y636451D01*
G01X948304Y646577D02*
X890326Y704555D01*
G01X1253607Y646577D02*
X948304D01*
G01X930137Y599863D02*
X1165315D01*
G01X898676Y631324D02*
X930137Y599863D01*
G01X896300Y633700D02*
X892400D01*
G01X898676Y631324D02*
X896300Y633700D01*
G01X871200Y655230D02*
X871240Y655190D01*
G01X865530Y655230D02*
X871200D01*
G01X871240Y655190D02*
Y651190D01*
G01X949982Y650627D02*
X1250415D01*
G01X894376Y706233D02*
X949982Y650627D01*
G01X956694Y626327D02*
X1186506D01*
G01X956693Y626326D02*
X956694Y626327D01*
G01X939915Y626326D02*
X956693D01*
G01X939914Y626327D02*
X939915Y626326D01*
G01X938315Y626327D02*
X939914D01*
G01X934758Y629884D02*
X938315Y626327D01*
G01X934758Y629885D02*
Y629884D01*
G01X932971Y607437D02*
X1172291D01*
G01X880058Y660350D02*
X932971Y607437D01*
G01X918871Y596155D02*
X892391Y622635D01*
G01X1165245Y596155D02*
X918871D01*
G01X892391Y622635D02*
X884801Y630225D01*
G01X883915Y704052D02*
Y781159D01*
G01X883914Y704051D02*
X883915Y704052D01*
G01X883914Y702375D02*
Y704051D01*
G01X881345Y667850D02*
X879042D01*
G01X956639Y749625D02*
X974939D01*
G01X935025Y771239D02*
X956639Y749625D01*
G01X866050Y760000D02*
X867050Y761000D01*
G01D02*
Y756500D01*
G01X888075Y782727D02*
Y703942D01*
G01X955800Y747600D02*
X933000Y770400D01*
G01X974100Y747600D02*
X955800D01*
G01X877576Y759879D02*
Y778906D01*
G01X877696Y759759D02*
X877576Y759879D01*
G01X877696Y755825D02*
Y759759D01*
G01X877576Y755705D02*
X877696Y755825D01*
G01X877576Y701799D02*
Y755705D01*
G01X877575Y701798D02*
X877576Y701799D01*
G01X877575Y700122D02*
Y701798D01*
G01X903000Y758975D02*
X903125Y758850D01*
G01X903000Y762700D02*
Y758975D01*
G01X881890Y704891D02*
Y780320D01*
G01X881889Y704890D02*
X881890Y704891D01*
G01X881889Y701536D02*
Y704890D01*
G01X896401Y819399D02*
Y707072D01*
G01X958120Y761010D02*
X956894Y762236D01*
G01X960370Y761010D02*
X958120D01*
G01X898426Y822843D02*
Y707911D01*
G01X892351Y813649D02*
Y705394D01*
G01X900451Y825257D02*
Y708750D01*
G01X885940Y781998D02*
Y703213D01*
G01X879601Y754866D02*
Y700960D01*
G01X879721Y754986D02*
X879601Y754866D01*
G01X879721Y760598D02*
Y754986D01*
G01X879601Y760718D02*
X879721Y760598D01*
G01X879601Y779745D02*
Y760718D01*
G01X890326Y704555D02*
Y809299D01*
G01X894376Y817043D02*
Y706233D01*
G01X907863Y797517D02*
X906008Y799372D01*
G01X918219Y797517D02*
X907863D01*
G01X920416Y795320D02*
X918219Y797517D01*
G01X925400Y795320D02*
X920416D01*
G01X903700Y801680D02*
Y803200D01*
G01X906008Y799372D02*
X903700Y801680D01*
G01X876290Y788784D02*
X865051D01*
G01X883915Y781159D02*
X876290Y788784D01*
G01X953990Y855990D02*
X952500Y854500D01*
G01X953990Y861030D02*
Y855990D01*
G01X957500Y849250D02*
X953000D01*
G01X952500Y849750D02*
Y854500D01*
G01X953000Y849250D02*
X952500Y849750D01*
G01X954159Y778168D02*
X955482D01*
G01X950831Y774840D02*
X954159Y778168D01*
G01X947600Y774840D02*
X950831D01*
G01X958149Y779010D02*
X960370D01*
G01X957307Y778168D02*
X958149Y779010D01*
G01X955482Y778168D02*
X957307D01*
G01X946634Y854300D02*
X946167Y853833D01*
G01X948300Y854300D02*
X946634D01*
G01X951430Y857430D02*
X948300Y854300D01*
G01X944000Y849250D02*
X948500D01*
G01Y851500D02*
X946167Y853833D01*
G01X948500Y849250D02*
Y851500D01*
G01X935025Y779175D02*
Y771239D01*
G01X931680Y782520D02*
X935025Y779175D01*
G01X925400Y782520D02*
X931680D01*
G01X947600D02*
X975573D01*
G01X868742Y817600D02*
X869989Y818847D01*
G01X957103Y802963D02*
X1004530D01*
G01X953417Y806649D02*
X957103Y802963D01*
G01X927205Y806649D02*
X953417D01*
G01X924527Y809327D02*
X927205Y806649D01*
G01X920136Y809327D02*
X924527D01*
G01X919000Y810463D02*
X920136Y809327D01*
G01X919000Y812400D02*
Y810463D01*
G01X917900Y813500D02*
X919000Y812400D01*
G01X916192Y813500D02*
X917900D01*
G01X913059Y810367D02*
X916192Y813500D01*
G01X904447Y815200D02*
X902560Y813313D01*
G01X908208Y815200D02*
X904447D01*
G01X909971Y813437D02*
X908208Y815200D01*
G01X909971Y809990D02*
Y813437D01*
G01X911994Y807967D02*
X909971Y809990D01*
G01X915344Y807967D02*
X911994D01*
G01X918250Y805061D02*
X915344Y807967D01*
G01X922424Y805061D02*
X918250D01*
G01X924886Y802599D02*
X922424Y805061D01*
G01X951739Y802599D02*
X924886D01*
G01X955425Y798913D02*
X951739Y802599D01*
G01X1006208Y798913D02*
X955425D01*
G01X877901Y792901D02*
X888075Y782727D01*
G01X866662Y792901D02*
X877901D01*
G01X869350Y798700D02*
X872600D01*
G01X868500Y799550D02*
X869350Y798700D01*
G01X924484Y812530D02*
Y812558D01*
G01X928339Y808675D02*
X924484Y812530D01*
G01X954255Y808675D02*
X928339D01*
G01X957942Y804988D02*
X954255Y808675D01*
G01X1003690Y804988D02*
X957942D01*
G01X953290Y795320D02*
X947600D01*
G01X953825Y794785D02*
X953290Y795320D01*
G01X977628Y794785D02*
X953825D01*
G01X931376Y779960D02*
X925400D01*
G01X933000Y778336D02*
X931376Y779960D01*
G01X933000Y770400D02*
Y778336D01*
G01X916892Y783500D02*
X917600D01*
G01X914780Y785612D02*
X916892Y783500D01*
G01X910888Y785612D02*
X914780D01*
G01X907800Y788700D02*
X910888Y785612D01*
G01X918802Y783500D02*
X917600D01*
G01X920382Y785080D02*
X918802Y783500D01*
G01X925400Y785080D02*
X920382D01*
G01X953390Y772968D02*
X955482D01*
G01X952702Y772280D02*
X953390Y772968D01*
G01X947600Y772280D02*
X952702D01*
G01X957412Y772968D02*
X960370Y770010D01*
G01X955482Y772968D02*
X957412D01*
G01X877576Y778906D02*
X873962Y782520D01*
G01X867299Y820160D02*
X870001Y822862D01*
G01X933167Y838833D02*
X943294D01*
G01X928267Y843733D02*
X933167Y838833D01*
G01X928267Y851314D02*
Y843733D01*
G01X937875Y860922D02*
X928267Y851314D01*
G01X903300Y763000D02*
X903000Y762700D01*
G01X903300Y763200D02*
Y763000D01*
G01X912800Y792801D02*
X912762D01*
G01X913313Y793314D02*
X912800Y792801D01*
G01X917211Y793314D02*
X913313D01*
G01X920599Y792760D02*
X925400D01*
G01X920045Y793314D02*
X920599Y792760D01*
G01X917211Y793314D02*
X920045D01*
G01X875452Y786758D02*
X864213D01*
G01X881890Y780320D02*
X875452Y786758D01*
G01X912250Y778000D02*
Y782800D01*
G01X920820Y778500D02*
X917600D01*
G01X921920Y777400D02*
X920820Y778500D01*
G01X925400Y777400D02*
X921920D01*
G01X914509Y778000D02*
X912250D01*
G01X915009Y778500D02*
X914509Y778000D01*
G01X917600Y778500D02*
X915009D01*
G01X954586Y796888D02*
X1007047D01*
G01X950900Y800574D02*
X954586Y796888D01*
G01X923664Y800574D02*
X950900D01*
G01X921311Y802927D02*
X923664Y800574D01*
G01X917446Y802927D02*
X921311D01*
G01X914482Y805891D02*
X917446Y802927D01*
G01X910609Y805891D02*
X914482D01*
G01X906166Y810334D02*
X910609Y805891D01*
G01X906166Y812784D02*
Y810334D01*
G01X911591Y800899D02*
X913597D01*
G01X909144Y803346D02*
X911591Y800899D01*
G01X921661Y797880D02*
X925400D01*
G01X918642Y800899D02*
X921661Y797880D01*
G01X913597Y800899D02*
X918642D01*
G01X874903Y812847D02*
X872750Y815000D01*
G01X874903Y811000D02*
Y812847D01*
G01X872710Y815040D02*
X867040D01*
G01X872750Y815000D02*
X872710Y815040D01*
G01X975877Y785080D02*
X947600D01*
G01X888100Y827700D02*
X896401Y819399D01*
G01X886583Y827700D02*
X888100D01*
G01X882447Y831836D02*
X886583Y827700D01*
G01X882447Y832137D02*
Y831836D01*
G01X863520Y812480D02*
X869000Y807000D01*
G01X874903Y805153D02*
Y807000D01*
G01X872750Y803000D02*
X874903Y805153D01*
G01Y807000D02*
X869000D01*
G01X976789Y792760D02*
X947600D01*
G01X868500Y803050D02*
X863241D01*
G01X953530Y769720D02*
X955482Y767768D01*
G01X947600Y769720D02*
X953530D01*
G01X956894Y766356D02*
X955482Y767768D01*
G01X956894Y762236D02*
Y766356D01*
G01X941000Y777400D02*
X947600D01*
G01X938051Y780349D02*
X941000Y777400D01*
G01X938051Y784338D02*
Y780349D01*
G01X931800Y790589D02*
X938051Y784338D01*
G01X931800Y791500D02*
Y790589D01*
G01X886342Y834927D02*
X898426Y822843D01*
G01X882410Y838859D02*
X886342Y834927D01*
G01X881702Y838859D02*
X882410D01*
G01X883750Y822250D02*
X892351Y813649D01*
G01X869709Y836291D02*
X883750Y822250D01*
G01X869709Y838846D02*
Y836291D01*
G01X865230Y843325D02*
X869709Y838846D01*
G01X943262Y779960D02*
X947600D01*
G01X941346Y781876D02*
X943262Y779960D01*
G01X941346Y789684D02*
Y781876D01*
G01X935730Y795300D02*
X941346Y789684D01*
G01X934800Y795300D02*
X935730D01*
G01X947600Y787640D02*
X976181D01*
G01X896283Y829425D02*
X900451Y825257D01*
G01X883553Y842155D02*
X896283Y829425D01*
G01X876862Y842155D02*
X883553D01*
G01X921047Y812672D02*
Y811463D01*
G01X923312Y814937D02*
X921047Y812672D01*
G01X925779Y814937D02*
X923312D01*
G01X929820Y810896D02*
X925779Y814937D01*
G01X954898Y810896D02*
X929820D01*
G01X958568Y807226D02*
X954898Y810896D01*
G01X956061Y855162D02*
X957095Y854128D01*
G01X956061Y856382D02*
Y855162D01*
G01X956550Y856871D02*
X956061Y856382D01*
G01X961973Y849250D02*
X957095Y854128D01*
G01X877062Y790876D02*
X885940Y781998D01*
G01X865823Y790876D02*
X877062D01*
G01X874800Y784546D02*
X879601Y779745D01*
G01X873124Y784546D02*
X874800D01*
G01X873123Y784545D02*
X873124Y784546D01*
G01X863562Y784545D02*
X873123D01*
G01X912574Y788194D02*
X917211D01*
G01X912030Y787650D02*
X912574Y788194D01*
G01X917215Y788190D02*
X917211Y788194D01*
G01X919786Y788190D02*
X917215D01*
G01X920336Y787640D02*
X919786Y788190D01*
G01X925400Y787640D02*
X920336D01*
G01X920156Y790200D02*
X925400D01*
G01X919606Y790750D02*
X920156Y790200D01*
G01X910425Y790750D02*
X919606D01*
G01X908543Y792632D02*
X910425Y790750D01*
G01X907237Y793938D02*
X908543Y792632D01*
G01X903221Y793938D02*
X907237D01*
G01X916855Y809547D02*
Y810934D01*
G01X919177Y807225D02*
X916855Y809547D01*
G01X923259Y807225D02*
X919177D01*
G01X925860Y804624D02*
X923259Y807225D01*
G01X952578Y804624D02*
X925860D01*
G01X956264Y800938D02*
X952578Y804624D01*
G01X1005369Y800938D02*
X956264D01*
G01X890326Y809299D02*
X874562Y825063D01*
G01X867684Y831941D02*
X874562Y825063D01*
G01X867684Y838007D02*
Y831941D01*
G01X864391Y841300D02*
X867684Y838007D01*
G01X880209Y831210D02*
X894376Y817043D01*
G01X947600Y790200D02*
X976485D01*
G01X948638Y924600D02*
X975206D01*
G01X925883Y901845D02*
X948638Y924600D01*
G01X925883Y896719D02*
Y901845D01*
G01X921263Y892099D02*
X925883Y896719D01*
G01X898669Y892099D02*
X921263D01*
G01X892020Y885450D02*
X898669Y892099D01*
G01X892020Y880364D02*
Y885450D01*
G01X949477Y922575D02*
X977222D01*
G01X927908Y901006D02*
X949477Y922575D01*
G01X927908Y895880D02*
Y901006D01*
G01X922102Y890074D02*
X927908Y895880D01*
G01X900101Y890074D02*
X922102D01*
G01X894580Y884553D02*
X900101Y890074D01*
G01X894580Y880364D02*
Y884553D01*
G01X894317Y870280D02*
X895346Y871309D01*
G01X894317Y865406D02*
Y870280D01*
G01X899700Y875663D02*
X895346Y871309D01*
G01X899700Y880364D02*
Y875663D01*
G01X951430Y861030D02*
Y857430D01*
G01X897140Y905360D02*
Y902564D01*
G01X890300Y912200D02*
X897140Y905360D01*
G01X867500Y912200D02*
X890300D01*
G01X909940Y871500D02*
Y880364D01*
G01Y865260D02*
X911080Y864120D01*
G01X909940Y871500D02*
Y865260D01*
G01X911080Y864120D02*
X915580D01*
G01X946346Y930900D02*
X972914D01*
G01X919808Y904362D02*
X946346Y930900D01*
G01X919808Y899236D02*
Y904362D01*
G01X918746Y898174D02*
X919808Y899236D01*
G01X895426Y898174D02*
X918746D01*
G01X894580Y899020D02*
X895426Y898174D01*
G01X894580Y902564D02*
Y899020D01*
G01X909940Y910665D02*
X897495Y923110D01*
G01X909940Y902564D02*
Y910665D01*
G01X892189Y863334D02*
X890117Y865406D01*
G01X895918Y863334D02*
X892189D01*
G01X900346Y867762D02*
X895918Y863334D01*
G01X900346Y871309D02*
Y867762D01*
G01Y872946D02*
Y871309D01*
G01X902260Y874860D02*
X900346Y872946D01*
G01X902260Y880364D02*
Y874860D01*
G01X947874Y926700D02*
X974442D01*
G01X923858Y902684D02*
X947874Y926700D01*
G01X923858Y897558D02*
Y902684D01*
G01X920424Y894124D02*
X923858Y897558D01*
G01X897164Y894124D02*
X920424D01*
G01X889460Y886420D02*
X897164Y894124D01*
G01X889460Y880364D02*
Y886420D01*
G01X893256Y858067D02*
X890117Y861206D01*
G01X898596Y858067D02*
X893256D01*
G01X900973D02*
X898596D01*
G01X907380Y864474D02*
X900973Y858067D01*
G01X907380Y880364D02*
Y864474D01*
G01X867100Y873500D02*
X867700D01*
G01X863200Y877400D02*
X867100Y873500D01*
G01X870500Y874000D02*
X872250D01*
G01X870000Y873500D02*
X870500Y874000D01*
G01X867700Y873500D02*
X870000D01*
G01X872250Y874000D02*
Y869500D01*
G01X907380Y909604D02*
X895899Y921085D01*
G01X907380Y902564D02*
Y909604D01*
G01X954208Y892439D02*
Y894134D01*
G01X948870Y887101D02*
X954208Y892439D01*
G01X948870Y883230D02*
Y887101D01*
G01X954750Y896608D02*
Y898500D01*
G01X954208Y896066D02*
X954750Y896608D01*
G01X954208Y894134D02*
Y896066D01*
G01X892322Y948365D02*
X917655Y973698D01*
G01X950316Y920550D02*
X978366D01*
G01X929933Y900167D02*
X950316Y920550D01*
G01X929933Y895041D02*
Y900167D01*
G01X922941Y888049D02*
X929933Y895041D01*
G01X900940Y888049D02*
X922941D01*
G01X897140Y884249D02*
X900940Y888049D01*
G01X897140Y880364D02*
Y884249D01*
G01X899649Y861227D02*
X902749Y864327D01*
G01X894338Y861227D02*
X899649D01*
G01X894317Y861206D02*
X894338Y861227D01*
G01X904820Y866398D02*
X902749Y864327D01*
G01X904820Y880364D02*
Y866398D01*
G01X937875Y885625D02*
Y869750D01*
G01X934709Y888791D02*
X937875Y885625D01*
G01X934709Y899335D02*
Y888791D01*
G01X940499Y905125D02*
X934709Y899335D01*
G01X947249Y911875D02*
X940499Y905125D01*
G01X947250Y911875D02*
X947249D01*
G01X937875Y869750D02*
Y860922D01*
G01X973246Y911875D02*
X947250D01*
G01X927260Y915245D02*
X923645Y911630D01*
G01X927260Y915620D02*
Y915245D01*
G01X917620Y905605D02*
X923645Y911630D01*
G01X917620Y902564D02*
Y905605D01*
G01X947185Y928875D02*
X973753D01*
G01X921833Y903523D02*
X947185Y928875D01*
G01X921833Y898397D02*
Y903523D01*
G01X919585Y896149D02*
X921833Y898397D01*
G01X893451Y896149D02*
X919585D01*
G01X892020Y897580D02*
X893451Y896149D01*
G01X892020Y902564D02*
Y897580D01*
G01X899700Y906421D02*
Y902564D01*
G01X891511Y914610D02*
X899700Y906421D01*
G01X866410Y914610D02*
X891511D01*
G01X918380Y911780D02*
Y915664D01*
G01X915060Y908460D02*
X918380Y911780D01*
G01X915060Y902564D02*
Y908460D01*
G01X922716Y915664D02*
X922760Y915620D01*
G01X918380Y915664D02*
X922716D01*
G01X904820Y908543D02*
X894303Y919060D01*
G01X904820Y902564D02*
Y908543D01*
G01X956550Y861030D02*
Y856871D01*
G01X912500Y911000D02*
X913000Y911500D01*
G01X912500Y902564D02*
Y911000D01*
G01X914260Y912760D02*
Y915620D01*
G01X913000Y911500D02*
X914260Y912760D01*
G01Y915620D02*
X909760D01*
G01X891483Y950390D02*
X915630Y974537D01*
G01X893014Y916728D02*
X864653D01*
G01X902260Y907482D02*
X893014Y916728D01*
G01X902260Y902564D02*
Y907482D01*
G01X913604Y984861D02*
X974513Y1045770D01*
G01X913604Y975375D02*
Y984861D01*
G01X890644Y952415D02*
X913604Y975375D01*
G01X909553Y986538D02*
X972835Y1049820D01*
G01X909553Y977052D02*
Y986538D01*
G01X889168Y956667D02*
X909553Y977052D01*
G01X917655Y983184D02*
X976191Y1041720D01*
G01X917655Y973698D02*
Y983184D01*
G01X911578Y985699D02*
X973674Y1047795D01*
G01X911578Y976213D02*
Y985699D01*
G01X889805Y954440D02*
X911578Y976213D01*
G01X907528Y1016682D02*
X943844Y1052998D01*
G01X907528Y977891D02*
Y1016682D01*
G01X888329Y958692D02*
X907528Y977891D01*
G01X915630Y984023D02*
X975352Y1043745D01*
G01X915630Y974537D02*
Y984023D01*
G01X943844Y1052998D02*
X1223634D01*
G01X959500Y1226250D02*
X955500D01*
G01X945500Y1219000D02*
X943500Y1221000D01*
G01X954000Y1219000D02*
X945500D01*
G01X955425Y1217575D02*
X954000Y1219000D01*
G01X955425Y1215500D02*
Y1217575D01*
G01X943500Y1221000D02*
Y1226250D01*
G01X952500Y1221500D02*
X951500Y1222500D01*
G01X954200Y1221500D02*
X952500D01*
G01X957000Y1218700D02*
X954200Y1221500D01*
G01X957000Y1215500D02*
Y1218700D01*
G01X951500Y1222500D02*
Y1226250D01*
G01D02*
X947500D01*
G01X989899Y364299D02*
X1036100Y410500D01*
G01X989899Y345222D02*
Y364299D01*
G01X991924Y362424D02*
X1014416Y384916D01*
G01X991924Y343892D02*
Y362424D01*
G01X1014979Y423228D02*
X1033200D01*
G01X1050828D02*
X1067200Y439600D01*
G01X1033200Y423228D02*
X1050828D01*
G01X1053300Y416600D02*
X1069800Y433100D01*
G01X1042200Y416600D02*
X1053300D01*
G01X1036100Y410500D02*
X1042200Y416600D01*
G01X1054400Y448500D02*
X1041600Y435700D01*
G01X1037314Y431414D02*
X1041600Y435700D01*
G01X1014573Y431414D02*
X1037314D01*
G01X1009628Y437230D02*
X1016557D01*
G01X1002209Y429811D02*
X1009628Y437230D01*
G01X1002209Y429803D02*
Y429811D01*
G01X1042140Y455800D02*
X1095100D01*
G01X1023570Y437230D02*
X1042140Y455800D01*
G01X1016557Y437230D02*
X1023570D01*
G01X1052600Y420400D02*
X1045300D01*
G01X1069000Y436800D02*
X1052600Y420400D01*
G01X1015257D02*
X1045300D01*
G01X1042634Y413375D02*
X1058623D01*
G01X1014416Y385157D02*
X1042634Y413375D01*
G01X1014416Y384916D02*
Y385157D01*
G01X1061000Y445600D02*
X1047900Y432500D01*
G01X1044789Y429389D02*
X1047900Y432500D01*
G01X1015412Y429389D02*
X1044789D01*
G01X1015018Y426131D02*
X1017500D01*
G01X1050131D02*
X1066500Y442500D01*
G01X1017500Y426131D02*
X1050131D01*
G01X977700Y512300D02*
X981500D01*
G01X976213Y513787D02*
X977700Y512300D01*
G01X976213Y519617D02*
Y513787D01*
G01X989700Y512300D02*
X981500D01*
G01X991688Y514288D02*
X989700Y512300D01*
G01X991688Y517437D02*
Y514288D01*
G01X962271Y553411D02*
X959889D01*
G01X980700Y539000D02*
X984200D01*
G01X978571Y541129D02*
X980700Y539000D01*
G01X978571Y545731D02*
Y541129D01*
G01X988943Y539000D02*
X984200D01*
G01X989498Y539555D02*
X988943Y539000D01*
G01X1031277Y661023D02*
X1116345D01*
G01X1008225Y684075D02*
X1031277Y661023D01*
G01X1035574Y663117D02*
X1132453D01*
G01X1011037Y687654D02*
X1035574Y663117D01*
G01X1029218Y658882D02*
X1006200Y681900D01*
G01X1114905Y658882D02*
X1029218D01*
G01X1037985Y665142D02*
X1133294D01*
G01X1015618Y687509D02*
X1037985Y665142D01*
G01X1008225Y716339D02*
Y684075D01*
G01X974939Y749625D02*
X1008225Y716339D01*
G01X1011037Y736868D02*
Y687654D01*
G01Y747056D02*
Y736868D01*
G01X975573Y782520D02*
X1011037Y747056D01*
G01X1032654Y690406D02*
Y697436D01*
G01X1049818Y673242D02*
X1032654Y690406D01*
G01X1136650Y673242D02*
X1049818D01*
G01X1032654Y739759D02*
X977628Y794785D01*
G01X1032654Y697436D02*
Y739759D01*
G01X1006200Y715500D02*
X974100Y747600D01*
G01X1006200Y681900D02*
Y715500D01*
G01X1015618Y700908D02*
Y687509D01*
G01Y745339D02*
X975877Y785080D01*
G01X1015618Y700908D02*
Y745339D01*
G01X1046773Y671217D02*
X1135811D01*
G01X1028089Y689901D02*
X1046773Y671217D01*
G01X1028089Y707561D02*
Y689901D01*
G01Y741460D02*
X976789Y792760D01*
G01X1028089Y707561D02*
Y741460D01*
G01X1040460Y667167D02*
X1134133D01*
G01X1019284Y688343D02*
X1040460Y667167D01*
G01X1019284Y721708D02*
Y688343D01*
G01Y744537D02*
Y721708D01*
G01X976181Y787640D02*
X1019284Y744537D01*
G01X1044109Y669192D02*
X1134972D01*
G01X1023243Y690058D02*
X1044109Y669192D01*
G01X1023243Y732861D02*
Y690058D01*
G01Y743442D02*
Y732861D01*
G01X976485Y790200D02*
X1023243Y743442D01*
G01X960370Y779010D02*
Y774510D01*
G01X1034131Y855984D02*
X1033065Y857050D01*
G01X1020860Y860940D02*
Y856130D01*
G01X1018300D02*
Y860925D01*
G01X1022914Y856130D02*
X1024550Y857766D01*
G01X1020860Y856130D02*
X1022914D01*
G01X1008453Y806886D02*
X1081128D01*
G01X1004530Y802963D02*
X1008453Y806886D01*
G01X1010131Y802836D02*
X1006208Y798913D01*
G01X1086753Y802836D02*
X1010131D01*
G01X1007613Y808911D02*
X1003690Y804988D01*
G01X1080288Y808911D02*
X1007613D01*
G01X960370Y770010D02*
Y765510D01*
G01X984120Y838620D02*
X983000Y837500D01*
G01X984120Y845050D02*
Y838620D01*
G01X983000Y833310D02*
Y837500D01*
G01X983070Y833240D02*
X983000Y833310D01*
G01X1010970Y800811D02*
X1085403D01*
G01X1007047Y796888D02*
X1010970Y800811D01*
G01X1034134Y848192D02*
X1033807Y847865D01*
G01X1034134Y851705D02*
Y848192D01*
G01X1031261Y847865D02*
X1033807D01*
G01X1029912Y849214D02*
X1031261Y847865D01*
G01X970840Y855574D02*
Y868660D01*
G01X967666Y852400D02*
X970840Y855574D01*
G01X963200Y852400D02*
X967666D01*
G01X961670Y853930D02*
X963200Y852400D01*
G01X961670Y861030D02*
Y853930D01*
G01X1003061Y807226D02*
X958568D01*
G01X1006771Y810936D02*
X1003061Y807226D01*
G01X1077816Y810936D02*
X1006771D01*
G01X966093Y849250D02*
X962000D01*
G01D02*
X961973D01*
G01X1009292Y804861D02*
X1005369Y800938D01*
G01X1081967Y804861D02*
X1009292D01*
G01X1015740Y852288D02*
X1020061Y847967D01*
G01X1015740Y856130D02*
Y852288D01*
G01X1020250Y847778D02*
Y842500D01*
G01X1020061Y847967D02*
X1020250Y847778D01*
G01X975206Y924600D02*
X1061873Y1011267D01*
G01X977222Y922575D02*
X1063591Y1008944D01*
G01X1033065Y857050D02*
X1029600D01*
G01Y860900D02*
X1028500Y862000D01*
G01X1029600Y857050D02*
Y860900D01*
G01X1020200Y861600D02*
X1020860Y860940D01*
G01X1018975Y861600D02*
X1020200D01*
G01X1018300Y860925D02*
X1018975Y861600D01*
G01X1026500Y862000D02*
X1028500D01*
G01X1024550Y860050D02*
X1026500Y862000D01*
G01X1024550Y857766D02*
Y860050D01*
G01X972914Y930900D02*
X1059569Y1017555D01*
G01X1039500Y883250D02*
Y878500D01*
G01D02*
Y874700D01*
G01X974219Y871410D02*
X971982Y873647D01*
G01X977210Y871410D02*
X974219D01*
G01X979120Y869500D02*
X977210Y871410D01*
G01X979120Y865050D02*
Y869500D01*
G01X972042Y873707D02*
Y877750D01*
G01X971982Y873647D02*
X972042Y873707D01*
G01Y877750D02*
X976242D01*
G01X974442Y926700D02*
X1061034Y1013292D01*
G01X1024250Y918250D02*
X1025500Y919500D01*
G01X1019875Y918250D02*
X1024250D01*
G01X1024024Y936000D02*
Y939306D01*
G01X1024507Y935517D02*
X1024024Y936000D01*
G01X1024507Y929750D02*
Y935517D01*
G01X1025500Y923500D02*
Y919500D01*
G01X1024507Y924493D02*
X1025500Y923500D01*
G01X1024507Y929750D02*
Y924493D01*
G01X959110Y890440D02*
X964170Y895500D01*
G01X959110Y883230D02*
Y890440D01*
G01X970834Y902164D02*
X964170Y895500D01*
G01X970834Y906599D02*
Y902164D01*
G01X1083475Y1019240D02*
X970834Y906599D01*
G01X978366Y920550D02*
X1056428Y998612D01*
G01X975288Y902954D02*
X972854Y900520D01*
G01X975288Y908189D02*
Y902954D01*
G01X1084314Y1017215D02*
X975288Y908189D01*
G01X963908Y891574D02*
X972854Y900520D01*
G01X963908Y891573D02*
Y891574D01*
G01X961670Y889335D02*
X963908Y891573D01*
G01X961670Y883230D02*
Y889335D01*
G01X1009666Y907250D02*
X1005500D01*
G01X1009719Y907303D02*
X1009666Y907250D01*
G01X1026566Y907303D02*
X1009719D01*
G01X1030862Y911599D02*
X1026566Y907303D01*
G01X1030862Y951946D02*
Y911599D01*
G01X1022080Y960709D02*
X973246Y911875D01*
G01X980484Y904534D02*
X978033Y902083D01*
G01X980484Y909671D02*
Y904534D01*
G01X1086003Y1015190D02*
X980484Y909671D01*
G01X964230Y888280D02*
Y883230D01*
G01X978033Y902083D02*
X964230Y888280D01*
G01X1005500Y910750D02*
X1016000D01*
G01X1001500Y916000D02*
X1003000D01*
G01X1000500Y915000D02*
X1001500Y916000D01*
G01X1000500Y910750D02*
Y915000D01*
G01X1004500Y916000D02*
X1003000D01*
G01X1005500Y915000D02*
X1004500Y916000D01*
G01X1005500Y910750D02*
Y915000D01*
G01X973753Y928875D02*
X1060195Y1015317D01*
G01X985678Y906562D02*
X983311Y904195D01*
G01X985678Y911829D02*
Y906562D01*
G01X1087014Y1013165D02*
X985678Y911829D01*
G01X980637Y901521D02*
X983311Y904195D01*
G01X980637Y901520D02*
Y901521D01*
G01X976897Y897780D02*
X980637Y901520D01*
G01X976896Y897780D02*
X976897D01*
G01X968665Y889549D02*
X976896Y897780D01*
G01X968665Y870835D02*
Y889549D01*
G01X970840Y868660D02*
X968665Y870835D01*
G01X989933Y869813D02*
Y872000D01*
G01X989120Y869000D02*
X989933Y869813D01*
G01X989120Y865050D02*
Y869000D01*
G01X989742Y874300D02*
Y876050D01*
G01X989933Y874109D02*
X989742Y874300D01*
G01X989933Y872000D02*
Y874109D01*
G01X989742Y876050D02*
X993942D01*
G01X984120Y869780D02*
X982500Y871400D01*
G01X984120Y865050D02*
Y869780D01*
G01X980400Y876008D02*
X980442Y876050D01*
G01X980400Y873500D02*
Y876008D01*
G01X982500Y871400D02*
X980400Y873500D01*
G01X980442Y876050D02*
X985542D01*
G01X974513Y1045770D02*
X1204035D01*
G01X976191Y1041720D02*
X1202357D01*
G01X1022080Y960728D02*
Y960709D01*
G01X975352Y1043745D02*
X1203196D01*
G01X972835Y1049820D02*
X1205713D01*
G01X973674Y1047795D02*
X1204874D01*
G01X970500Y1205000D02*
X975750D01*
G01X970284D02*
X970500D01*
G01X969908Y1205376D02*
X970284Y1205000D01*
G01X968524Y1205376D02*
X969908D01*
G01X967975Y1205925D02*
X968524Y1205376D01*
G01X965000Y1205925D02*
X967975D01*
G01X975750Y1217000D02*
Y1221000D01*
G01X971800Y1217000D02*
X975750D01*
G01X970500Y1215700D02*
X971800Y1217000D01*
G01X970500Y1213000D02*
Y1215700D01*
G01Y1211400D02*
Y1213000D01*
G01X968175Y1209075D02*
X970500Y1211400D01*
G01X965000Y1209075D02*
X968175D01*
G01X972000Y1209000D02*
X975750D01*
G01X971400D02*
X972000D01*
G01X970026Y1207626D02*
X971400Y1209000D01*
G01X969062Y1207626D02*
X970026D01*
G01X968936Y1207500D02*
X969062Y1207626D01*
G01X965000Y1207500D02*
X968936D01*
G01X975750Y1213000D02*
Y1209000D01*
G01X958575Y1220075D02*
X959500Y1221000D01*
G01X958575Y1215500D02*
Y1220075D01*
G01X959500Y1221000D02*
Y1226250D01*
G01X967500Y1220000D02*
Y1221000D01*
G01X963000Y1215500D02*
X967500Y1220000D01*
G01X961724Y1215500D02*
X963000D01*
G01X967500Y1221000D02*
Y1226250D01*
G01X982172Y1176631D02*
X961878Y1156337D01*
G01X1008658Y1189017D02*
X1070466D01*
G01X996272Y1176631D02*
X1008658Y1189017D01*
G01X982172Y1176631D02*
X996272D01*
G01X963500Y1221000D02*
Y1222500D01*
G01X960150Y1217650D02*
X963500Y1221000D01*
G01X960150Y1215500D02*
Y1217650D01*
G01X963500Y1222500D02*
Y1226250D01*
G01X967000Y1210650D02*
X965000D01*
G01X968000Y1211650D02*
X967000Y1210650D01*
G01X968000Y1217600D02*
Y1211650D01*
G01X972000Y1221600D02*
X968000Y1217600D01*
G01X972000Y1223400D02*
Y1221600D01*
G01X973600Y1225000D02*
X972000Y1223400D01*
G01X975750Y1225000D02*
X973600D01*
G01X996514Y1179800D02*
X987300D01*
G01X1007776Y1191062D02*
X996514Y1179800D01*
G01X1014977Y1191062D02*
X1007776D01*
G01X1015445Y1191530D02*
X1014977Y1191062D01*
G01X1068569Y1191530D02*
X1015445D01*
G01X981314Y1179800D02*
X959876Y1158362D01*
G01X987300Y1179800D02*
X981314D01*
G01X1028443Y1448399D02*
X1038303D01*
G01X1027443Y1447399D02*
X1028443Y1448399D01*
G01X1027443Y1444649D02*
Y1447399D01*
G01X1048553Y1448399D02*
X1043606D01*
G01X1038303D02*
X1043606D01*
G01X1046960Y1464391D02*
X1040663D01*
G01X1049260Y1466691D02*
X1046960Y1464391D01*
G01X1040663D02*
X1031163D01*
G01X1140425Y465225D02*
X1143720Y468520D01*
G01X1117903Y465225D02*
X1140425D01*
G01X1092278Y439600D02*
X1117903Y465225D01*
G01X1067200Y439600D02*
X1092278D01*
G01X1118694Y460288D02*
X1136100D01*
G01X1091506Y433100D02*
X1118694Y460288D01*
G01X1069800Y433100D02*
X1091506D01*
G01X1088000Y448500D02*
X1054400D01*
G01X1092342Y436800D02*
X1069000D01*
G01X1118742Y463200D02*
X1092342Y436800D01*
G01X1142300Y463200D02*
X1118742D01*
G01X1147440Y468340D02*
X1142300Y463200D01*
G01X1147440Y473040D02*
Y468340D01*
G01X1058623Y413375D02*
X1067872Y422624D01*
G01X1076323Y431075D02*
X1067872Y422624D01*
G01X1092345Y431075D02*
X1076323D01*
G01X1115770Y454500D02*
X1092345Y431075D01*
G01X1139400Y454500D02*
X1115770D01*
G01X1149900Y465000D02*
X1139400Y454500D01*
G01X1089200Y445600D02*
X1061000D01*
G01X1092000Y448400D02*
X1089200Y445600D01*
G01X1136928Y470418D02*
X1139330Y472820D01*
G01X1132300Y470418D02*
X1136928D01*
G01X1130494Y468612D02*
X1132300Y470418D01*
G01X1118426Y468612D02*
X1130494D01*
G01X1092314Y442500D02*
X1118426Y468612D01*
G01X1066500Y442500D02*
X1092314D01*
G01X1143100Y523700D02*
X1153700Y513100D01*
G01X1116973Y523700D02*
X1143100D01*
G01X1113530Y527143D02*
X1116973Y523700D01*
G01X1116345Y661023D02*
X1118505Y658863D01*
G01X1184809Y618747D02*
X1134600D01*
G01X1136346Y659224D02*
X1227424D01*
G01X1132453Y663117D02*
X1136346Y659224D01*
G01X1131963Y621663D02*
X1129500Y619200D01*
G01X1185442Y621663D02*
X1131963D01*
G01X1137187Y661249D02*
X1224496D01*
G01X1133294Y665142D02*
X1137187Y661249D01*
G01X1138026Y663274D02*
X1223352D01*
G01X1134133Y667167D02*
X1138026Y663274D01*
G01X1115825Y621993D02*
X1120959D01*
G01D02*
X1125025D01*
G01X1138865Y665299D02*
X1222513D01*
G01X1134972Y669192D02*
X1138865Y665299D01*
G01X1060985Y689387D02*
X1059927Y688329D01*
G01X1060985Y751763D02*
Y689387D01*
G01X1081391Y772169D02*
X1060985Y751763D01*
G01X1057806Y680253D02*
X1057826Y680233D01*
G01X1057806Y690406D02*
Y680253D01*
G01X1058960Y691560D02*
X1057806Y690406D01*
G01X1058960Y752602D02*
Y691560D01*
G01X1080602Y774244D02*
X1058960Y752602D01*
G01X1064220Y683755D02*
X1064216Y683751D01*
G01X1064220Y751965D02*
Y683755D01*
G01X1079409Y767154D02*
X1064220Y751965D01*
G01X1071179Y751979D02*
Y682315D01*
G01X1078600Y759400D02*
X1071179Y751979D01*
G01X1106416Y759400D02*
X1078600D01*
G01X1109593Y762577D02*
X1106416Y759400D01*
G01X1056104Y697112D02*
X1056116Y697100D01*
G01X1056104Y753104D02*
Y697112D01*
G01X1082800Y779800D02*
X1056104Y753104D01*
G01X1140298Y684085D02*
X1231285D01*
G01X1133989Y677776D02*
X1140298Y684085D01*
G01X1107674Y677776D02*
X1133989D01*
G01X1140543Y669349D02*
X1136650Y673242D01*
G01X1219720Y669349D02*
X1140543D01*
G01X1140888Y681090D02*
X1214657D01*
G01X1135211Y675413D02*
X1140888Y681090D01*
G01X1103770Y675413D02*
X1135211D01*
G01X1067554Y752054D02*
Y694447D01*
G01X1080579Y765079D02*
X1067554Y752054D01*
G01X1139704Y667324D02*
X1221674D01*
G01X1135811Y671217D02*
X1139704Y667324D01*
G01X1116536Y772169D02*
X1081391D01*
G01X1119042Y769663D02*
X1116536Y772169D01*
G01X1107087Y774244D02*
X1080602D01*
G01X1109593Y776750D02*
X1107087Y774244D01*
G01X1111021Y767154D02*
X1079409D01*
G01X1113530Y769663D02*
X1111021Y767154D01*
G01X1117615Y788413D02*
X1178053D01*
G01X1115105Y790923D02*
X1117615Y788413D01*
G01X1111028Y809681D02*
X1113530Y812183D01*
G01X1083923Y809681D02*
X1111028D01*
G01X1081128Y806886D02*
X1083923Y809681D01*
G01X1111670Y779800D02*
X1082800D01*
G01X1113066Y778404D02*
X1111670Y779800D01*
G01X1113451Y778404D02*
X1113066D01*
G01X1115105Y776750D02*
X1113451Y778404D01*
G01X1087000Y802589D02*
X1086753Y802836D01*
G01X1107086Y802589D02*
X1087000D01*
G01X1109593Y805096D02*
X1107086Y802589D01*
G01X1116032Y786338D02*
X1181588D01*
G01X1113530Y783836D02*
X1116032Y786338D01*
G01X1086063Y814686D02*
X1080288Y808911D01*
G01X1110521Y814686D02*
X1086063D01*
G01X1115105Y819270D02*
X1110521Y814686D01*
G01X1122068Y780810D02*
X1186580D01*
G01X1119042Y783836D02*
X1122068Y780810D01*
G01X1117360Y801840D02*
X1174180D01*
G01X1113530Y798010D02*
X1117360Y801840D01*
G01X1110523Y800514D02*
X1115105Y805096D01*
G01X1085700Y800514D02*
X1110523D01*
G01X1085403Y800811D02*
X1085700Y800514D01*
G01X1112603Y765079D02*
X1080579D01*
G01X1115105Y762577D02*
X1112603Y765079D01*
G01X1083641Y816761D02*
X1077816Y810936D01*
G01X1107084Y816761D02*
X1083641D01*
G01X1109593Y819270D02*
X1107084Y816761D01*
G01X1112097Y793427D02*
X1175097D01*
G01X1109593Y790923D02*
X1112097Y793427D01*
G01X1121550Y795502D02*
X1171698D01*
G01X1119042Y798010D02*
X1121550Y795502D01*
G01X1084752Y807646D02*
X1081967Y804861D01*
G01X1089399Y807646D02*
X1084752D01*
G01X1089439Y807606D02*
X1089399Y807646D01*
G01X1114465Y807606D02*
X1089439D01*
G01X1119042Y812183D02*
X1114465Y807606D01*
G01X1141639Y928659D02*
X1199131D01*
G01X1140150Y930148D02*
X1141639Y928659D01*
G01X1118109Y930148D02*
X1140150D01*
G01X1113530Y925569D02*
X1118109Y930148D01*
G01X1118113Y915979D02*
X1113530Y911396D01*
G01X1145621Y915979D02*
X1118113D01*
G01X1153117Y908483D02*
X1145621Y915979D01*
G01X1117614Y906818D02*
X1115105Y904309D01*
G01X1137220Y906818D02*
X1117614D01*
G01X1158038Y886000D02*
X1137220Y906818D01*
G01X1114177Y908893D02*
X1109593Y904309D01*
G01X1142207Y908893D02*
X1114177D01*
G01X1158500Y892600D02*
X1142207Y908893D01*
G01X1114174Y923063D02*
X1181037D01*
G01X1109593Y918482D02*
X1114174Y923063D01*
G01X1121546Y913900D02*
X1119042Y911396D01*
G01X1143595Y913900D02*
X1121546D01*
G01X1157995Y899500D02*
X1143595Y913900D01*
G01X1140935Y925569D02*
X1199357D01*
G01X1138431Y928073D02*
X1140935Y925569D01*
G01X1121546Y928073D02*
X1138431D01*
G01X1119042Y925569D02*
X1121546Y928073D01*
G01X1117611Y920988D02*
X1178312D01*
G01X1115105Y918482D02*
X1117611Y920988D01*
G01X1083214Y1032608D02*
X1160314D01*
G01X1065857Y1015251D02*
X1083214Y1032608D01*
G01X1065857Y1014950D02*
Y1015251D01*
G01X1062174Y1011267D02*
X1065857Y1014950D01*
G01X1061873Y1011267D02*
X1062174D01*
G01X1083937Y1029290D02*
X1200467D01*
G01X1063591Y1008944D02*
X1083937Y1029290D01*
G01X1081709Y1039695D02*
X1059569Y1017555D01*
G01X1201518Y1039695D02*
X1081709D01*
G01X1200626Y1034859D02*
X1124848D01*
G01X1082601D02*
X1124848D01*
G01X1063832Y1016090D02*
X1082601Y1034859D01*
G01X1063832Y1015789D02*
Y1016090D01*
G01X1061335Y1013292D02*
X1063832Y1015789D01*
G01X1061034Y1013292D02*
X1061335D01*
G01X1204789Y1019240D02*
X1083475D01*
G01X1085081Y1027265D02*
X1199628D01*
G01X1056428Y998612D02*
X1085081Y1027265D01*
G01X1203949Y1017215D02*
X1084314D01*
G01X1203110Y1015190D02*
X1086003D01*
G01X1082335Y1037457D02*
X1093332D01*
G01X1061807Y1016929D02*
X1082335Y1037457D01*
G01X1061807Y1016628D02*
Y1016929D01*
G01X1060496Y1015317D02*
X1061807Y1016628D01*
G01X1060195Y1015317D02*
X1060496D01*
G01X1200892Y1037457D02*
X1093332D01*
G01X1202271Y1013165D02*
X1087014D01*
G01X1070466Y1189017D02*
X1072931Y1191482D01*
G01X1105862Y1391273D02*
X1111012D01*
G01X1113012D02*
X1111012D01*
G01X1113937Y1390348D02*
X1113012Y1391273D01*
G01X1116612Y1390348D02*
X1113937D01*
G01X1105862Y1387273D02*
X1109612D01*
G01X1110112D02*
X1109612D01*
G01X1111612Y1388773D02*
X1110112Y1387273D01*
G01X1116612Y1388773D02*
X1111612D01*
G01X1105862Y1383273D02*
Y1387273D01*
G01X1111112Y1384987D02*
Y1383273D01*
G01X1113323Y1387198D02*
X1111112Y1384987D01*
G01X1116612Y1387198D02*
X1113323D01*
G01X1107112Y1379273D02*
X1111112Y1383273D01*
G01X1105862Y1379273D02*
X1107112D01*
G01X1105850Y1379261D02*
X1105862Y1379273D01*
G01X1105850Y1375200D02*
Y1379261D01*
G01X1118301Y1375662D02*
Y1374458D01*
G01X1121462Y1378823D02*
X1118301Y1375662D01*
G01X1121462Y1380773D02*
Y1378823D01*
G01X1118301Y1372362D02*
Y1374458D01*
G01X1118112Y1372173D02*
X1118301Y1372362D01*
G01X1118112Y1370023D02*
Y1372173D01*
G01X1114112Y1376273D02*
Y1374773D01*
G01X1118612Y1380773D02*
X1114112Y1376273D01*
G01X1119888Y1380773D02*
X1118612D01*
G01X1114112Y1374773D02*
Y1370023D01*
G01X1126112Y1374773D02*
X1130112D01*
G01X1125337Y1375548D02*
X1126112Y1374773D01*
G01X1125337Y1376899D02*
Y1375548D01*
G01X1124586Y1377650D02*
X1125337Y1376899D01*
G01X1124586Y1379326D02*
Y1377650D01*
G01X1124612Y1379352D02*
X1124586Y1379326D01*
G01X1124612Y1380773D02*
Y1379352D01*
G01X1134112Y1370023D02*
X1130112D01*
G01D02*
Y1374773D01*
G01X1123037Y1380773D02*
Y1374473D01*
G01X1122112Y1373148D02*
Y1370023D01*
G01X1123037Y1374073D02*
X1122112Y1373148D01*
G01X1123037Y1374473D02*
Y1374073D01*
G01X1122112Y1370023D02*
X1126112D01*
G01X1138112D02*
Y1375273D01*
G01X1136012Y1377373D02*
X1138112Y1375273D01*
G01X1127727Y1377373D02*
X1136012D01*
G01X1126187Y1378913D02*
X1127727Y1377373D01*
G01X1126187Y1380773D02*
Y1378913D01*
G01X1114612Y1385623D02*
X1116612D01*
G01X1113612Y1384623D02*
X1114612Y1385623D01*
G01X1113612Y1378812D02*
Y1384623D01*
G01X1111300Y1376500D02*
X1113612Y1378812D01*
G01X1111300Y1373288D02*
Y1376500D01*
G01X1109612Y1371600D02*
X1111300Y1373288D01*
G01X1109212Y1371200D02*
X1109612Y1371600D01*
G01X1105850Y1371200D02*
X1109212D01*
G01X1277678Y417098D02*
X1208710Y486066D01*
G01X1294740Y402900D02*
X1211879Y485761D01*
G01X1296765Y403739D02*
X1214794Y485710D01*
G01X1205961Y485649D02*
X1248784Y442826D01*
G01X1149900Y477000D02*
Y465000D01*
G01X1265295Y421223D02*
X1232660Y453858D01*
G01X1203936Y482582D02*
X1232660Y453858D01*
G01X1250648Y425686D02*
X1234254Y442080D01*
G01X1199886Y476448D02*
X1234254Y442080D01*
G01X1194465Y476796D02*
X1247949Y423312D01*
G01X1218485Y462942D02*
X1216078Y465349D01*
G01X1218485Y462941D02*
Y462942D01*
G01X1245899Y435527D02*
X1218485Y462941D01*
G01X1214129Y467298D02*
X1216078Y465349D01*
G01X1214128Y467298D02*
X1214129D01*
G01X1201911Y479515D02*
X1214128Y467298D01*
G01X1192440Y473729D02*
Y568960D01*
G01X1245567Y420602D02*
X1192440Y473729D01*
G01X1208710Y486066D02*
Y589776D01*
G01X1211879Y485761D02*
Y591677D01*
G01X1225314Y502576D02*
X1253343Y474547D01*
G01X1225314Y592063D02*
Y502576D01*
G01X1214794Y485710D02*
Y592311D01*
G01X1205961Y571712D02*
Y485649D01*
G01X1217836Y504326D02*
Y592133D01*
G01X1249292Y472870D02*
X1217836Y504326D01*
G01X1232508Y501110D02*
X1257393Y476225D01*
G01X1232508Y590597D02*
Y501110D01*
G01X1236183Y500299D02*
Y589786D01*
G01X1259419Y477063D02*
X1236183Y500299D01*
G01X1243028Y499182D02*
Y588669D01*
G01X1263469Y478741D02*
X1243028Y499182D01*
G01X1153700Y480800D02*
X1149900Y477000D01*
G01X1153700Y513100D02*
Y480800D01*
G01X1203936Y570873D02*
Y482582D01*
G01X1228832Y501922D02*
X1255368Y475386D01*
G01X1228832Y591409D02*
Y501922D01*
G01X1199886Y569195D02*
Y476448D01*
G01X1164529Y604552D02*
X1199886Y569195D01*
G01X1239732Y499614D02*
X1261444Y477902D01*
G01X1239732Y589101D02*
Y499614D01*
G01X1194465Y570713D02*
Y476796D01*
G01X1221512Y503514D02*
X1251318Y473708D01*
G01X1221512Y591321D02*
Y503514D01*
G01X1201911Y570034D02*
Y479515D01*
G01X1200821Y571124D02*
X1201911Y570034D01*
G01X1192440Y568960D02*
X1165245Y596155D01*
G01X1246748Y587813D02*
X1194059Y640502D01*
G01X1208710Y589776D02*
X1182831Y615655D01*
G01X1211879Y591677D02*
X1184809Y618747D01*
G01X1227424Y659224D02*
X1232490Y664290D01*
G01X1189025Y628352D02*
X1225314Y592063D01*
G01X1196757Y644552D02*
X1216040Y625269D01*
G01X1252800Y588509D02*
X1216040Y625269D01*
G01X1214794Y592311D02*
X1185442Y621663D01*
G01X1205415Y572258D02*
X1205961Y571712D01*
G01X1205415Y586607D02*
Y572258D01*
G01X1178851Y613171D02*
X1205415Y586607D01*
G01X1217836Y592133D02*
X1185667Y624302D01*
G01X1190703Y632402D02*
X1232508Y590597D01*
G01X1236183Y589786D02*
X1191542Y634427D01*
G01X1243028Y588669D02*
X1193220Y638477D01*
G01X1234652Y666328D02*
X1236690Y664290D01*
G01X1224496Y661249D02*
X1229575Y666328D01*
G01X1202846Y571963D02*
X1203936Y570873D01*
G01X1202846Y582585D02*
Y571963D01*
G01X1175335Y610096D02*
X1202846Y582585D01*
G01X1189864Y630377D02*
X1228832Y591409D01*
G01X1223352Y663274D02*
X1228568Y668490D01*
G01X1235102Y656702D02*
X1259100Y680700D01*
G01X1194898Y642527D02*
X1249618Y587807D01*
G01X1192381Y636452D02*
X1239732Y589101D01*
G01X1165315Y599863D02*
X1194465Y570713D01*
G01X1186506Y626327D02*
X1221512Y591321D01*
G01X1200821Y578907D02*
Y571124D01*
G01X1172291Y607437D02*
X1200821Y578907D01*
G01X1222513Y665299D02*
X1227742Y670528D01*
G01X1212703Y799013D02*
Y758435D01*
G01Y749411D02*
Y758435D01*
G01X1212587Y749295D02*
X1212703Y749411D01*
G01X1231285Y684085D02*
X1232490Y685290D01*
G01X1225099Y674728D02*
X1219720Y669349D01*
G01X1234652Y674728D02*
X1225099D01*
G01X1236690Y672690D02*
X1234652Y674728D01*
G01X1214657Y681090D02*
X1232490D01*
G01X1226837Y712119D02*
Y801500D01*
G01X1210283Y695565D02*
X1226837Y712119D01*
G01X1223679Y711838D02*
Y801794D01*
G01X1209803Y697962D02*
X1223679Y711838D01*
G01X1207468Y697962D02*
X1209803D01*
G01X1221654Y713331D02*
Y800955D01*
G01X1209931Y701608D02*
X1221654Y713331D01*
G01X1229575Y666328D02*
X1234652D01*
G01X1227040Y672690D02*
X1232490D01*
G01X1221674Y667324D02*
X1227040Y672690D01*
G01X1218574Y716421D02*
Y801171D01*
G01X1206414Y704261D02*
X1218574Y716421D01*
G01X1228568Y668490D02*
X1232490D01*
G01X1206937Y801915D02*
Y755002D01*
G01Y750745D02*
Y755002D01*
G01X1212587Y745095D02*
X1206937Y750745D01*
G01X1234652Y670528D02*
X1236690Y668490D01*
G01X1227742Y670528D02*
X1234652D01*
G01X1190191Y821525D02*
X1212703Y799013D01*
G01X1190191Y855206D02*
Y821525D01*
G01X1205372Y870387D02*
X1190191Y855206D01*
G01X1178053Y788413D02*
X1180520Y790880D01*
G01X1181588Y786338D02*
X1186690Y791440D01*
G01X1186580Y780810D02*
X1190995Y776395D01*
G01X1201942Y850337D02*
X1226837Y875232D01*
G01X1201942Y826395D02*
Y850337D01*
G01X1226837Y801500D02*
X1201942Y826395D01*
G01X1199917Y851176D02*
X1223679Y874938D01*
G01X1199917Y825556D02*
Y851176D01*
G01X1223679Y801794D02*
X1199917Y825556D01*
G01X1197892Y852015D02*
X1221654Y875777D01*
G01X1197892Y824717D02*
Y852015D01*
G01X1221654Y800955D02*
X1197892Y824717D01*
G01X1174180Y801840D02*
X1177300Y804960D01*
G01X1195867Y852854D02*
X1219629Y876616D01*
G01X1195867Y823878D02*
Y852854D01*
G01X1218574Y801171D02*
X1195867Y823878D01*
G01X1255741Y855959D02*
X1231844D01*
G01D02*
Y849250D01*
G01X1175097Y793427D02*
X1179690Y798020D01*
G01X1188166Y820686D02*
X1206937Y801915D01*
G01X1188166Y856045D02*
Y820686D01*
G01X1203347Y871226D02*
X1188166Y856045D01*
G01X1217111Y829350D02*
Y825000D01*
G01X1171715Y795485D02*
X1173990Y797760D01*
G01X1171698Y795502D02*
X1171715Y795485D01*
G01X1217111Y842032D02*
Y836182D01*
G01D02*
Y829350D01*
G01X1233230Y937374D02*
Y999391D01*
G01X1269904Y900700D02*
X1233230Y937374D01*
G01X1231205Y935658D02*
X1268321Y898542D01*
G01X1231205Y998552D02*
Y935658D01*
G01X1205372Y922418D02*
Y870387D01*
G01X1199131Y928659D02*
X1205372Y922418D01*
G01X1181550Y906100D02*
X1184750D01*
G01X1183049Y908483D02*
X1153117D01*
G01X1184750Y906782D02*
X1183049Y908483D01*
G01X1184750Y906100D02*
Y906782D01*
G01X1239489Y939707D02*
Y1001724D01*
G01X1272196Y907000D02*
X1239489Y939707D01*
G01X1184750Y889200D02*
Y886000D01*
G01D02*
X1158038D01*
G01X1235256Y938212D02*
Y1000229D01*
G01X1270568Y902900D02*
X1235256Y938212D01*
G01X1184750Y896300D02*
Y892600D01*
G01D02*
X1158500D01*
G01X1241842Y940219D02*
X1269962Y912099D01*
G01X1241842Y1002235D02*
Y940219D01*
G01X1189268Y918091D02*
X1188509Y918850D01*
G01X1193544Y918091D02*
X1189268D01*
G01X1187667Y919692D02*
X1188509Y918850D01*
G01X1184408Y919692D02*
X1187667D01*
G01X1181037Y923063D02*
X1184408Y919692D01*
G01X1226837Y875232D02*
Y997191D01*
G01X1229180Y934819D02*
X1267802Y896197D01*
G01X1229180Y997713D02*
Y934819D01*
G01X1223679Y874938D02*
Y997485D01*
G01X1221654Y875777D02*
Y996646D01*
G01X1237464Y938868D02*
Y1000885D01*
G01X1271370Y904962D02*
X1237464Y938868D01*
G01X1219629Y876616D02*
Y995807D01*
G01X1181774Y896524D02*
X1184750Y899500D01*
G01X1180090Y896524D02*
X1181774D01*
G01X1184750Y899500D02*
X1157995D01*
G01X1203347Y921579D02*
Y871226D01*
G01X1199357Y925569D02*
X1203347Y921579D01*
G01X1189649Y912331D02*
X1189224Y912756D01*
G01X1193474Y912331D02*
X1189649D01*
G01X1185244Y916736D02*
X1189224Y912756D01*
G01X1182564Y916736D02*
X1185244D01*
G01X1178312Y920988D02*
X1182564Y916736D01*
G01X1243867Y941058D02*
X1270800Y914125D01*
G01X1243867Y1003074D02*
Y941058D01*
G01X1200013Y1032608D02*
X1160314D01*
G01X1233230Y999391D02*
X1200013Y1032608D01*
G01X1200467Y1029290D02*
X1231205Y998552D01*
G01X1204035Y1045770D02*
X1246292Y1003513D01*
G01X1205713Y1049820D02*
X1250343Y1005190D01*
G01X1239489Y1001724D02*
X1201518Y1039695D01*
G01X1235256Y1000229D02*
X1200626Y1034859D01*
G01X1202357Y1041720D02*
X1241842Y1002235D01*
G01X1204874Y1047795D02*
X1248317Y1004352D01*
G01X1205974Y1018055D02*
X1204789Y1019240D01*
G01X1205974Y1018054D02*
Y1018055D01*
G01X1226837Y997191D02*
X1205974Y1018054D01*
G01X1199628Y1027265D02*
X1229180Y997713D01*
G01X1223679Y997485D02*
X1203949Y1017215D01*
G01X1221654Y996646D02*
X1203110Y1015190D01*
G01X1252800Y1037700D02*
X1237502Y1052998D01*
G01X1237464Y1000885D02*
X1200892Y1037457D01*
G01X1219629Y995807D02*
X1202271Y1013165D01*
G01X1203196Y1043745D02*
X1243867Y1003074D01*
G01X1237502Y1052998D02*
X1223634D01*
G01X1235600Y1326833D02*
Y1335151D01*
G01X1202394D02*
Y1326833D01*
G01X1197394Y1335151D02*
Y1326833D01*
G01X1230600D02*
Y1335151D01*
G01X1235600Y1339033D02*
X1236600Y1340033D01*
G01X1235600Y1335151D02*
Y1339033D01*
G01X1236600Y1340033D02*
X1241600D01*
G01X1208394D02*
X1203394D01*
G01X1202394Y1339033D02*
Y1335151D01*
G01X1203394Y1340033D02*
X1202394Y1339033D01*
G01X1193894Y1340033D02*
X1198894D01*
G01X1197394Y1336989D02*
Y1335151D01*
G01X1198894Y1338489D02*
X1197394Y1336989D01*
G01X1198894Y1340033D02*
Y1338489D01*
G01X1232100D02*
Y1340033D01*
G01X1230600Y1336989D02*
X1232100Y1338489D01*
G01X1230600Y1335151D02*
Y1336989D01*
G01X1232100Y1340033D02*
X1227100D01*
G01X1322450Y33800D02*
X1352900D01*
G01X1318000Y38250D02*
X1322450Y33800D01*
G01X1313700Y54050D02*
X1317800D01*
G01X1311100Y58300D02*
X1312100D01*
G01X1307200Y54400D02*
X1311100Y58300D01*
G01X1307200Y53060D02*
Y54400D01*
G01X1313700Y56700D02*
X1312100Y58300D01*
G01X1313700Y54050D02*
Y56700D01*
G01X1317900Y62500D02*
Y59900D01*
G01X1314750Y65650D02*
X1317900Y62500D01*
G01X1311700Y65650D02*
X1314750D01*
G01X1317900Y54150D02*
X1317800Y54050D01*
G01X1317900Y59900D02*
Y54150D01*
G01X1313650Y50500D02*
X1313700Y50550D01*
G01X1307200Y50500D02*
X1313650D01*
G01X1306950Y57450D02*
Y59950D01*
G01X1303500Y54000D02*
X1306950Y57450D01*
G01X1303500Y48800D02*
Y54000D01*
G01X1302640Y47940D02*
X1303500Y48800D01*
G01X1299800Y47940D02*
X1302640D01*
G01X1305050Y61850D02*
X1306950Y59950D01*
G01X1305050Y63900D02*
Y61850D01*
G01Y69550D02*
Y68900D01*
G01X1302200Y72400D02*
X1305050Y69550D01*
G01X1297200Y72400D02*
X1302200D01*
G01X1295000Y74600D02*
X1297200Y72400D01*
G01X1295000Y88100D02*
Y74600D01*
G01X1299500Y92600D02*
X1295000Y88100D01*
G01X1299500Y102000D02*
Y92600D01*
G01X1305050Y68900D02*
Y63900D01*
G01X1298300Y50500D02*
X1299800D01*
G01X1296700Y48900D02*
X1298300Y50500D01*
G01X1296700Y42900D02*
Y48900D01*
G01X1297850Y41750D02*
X1296700Y42900D01*
G01X1303500Y41750D02*
X1297850D01*
G01X1318000D02*
X1313000D01*
G01D02*
X1308000D01*
G01D02*
X1303500D01*
G01X1317900Y71661D02*
Y68900D01*
G01X1334250Y88011D02*
X1317900Y71661D01*
G01X1334250Y104300D02*
Y88011D01*
G01X1315059Y69150D02*
X1311700D01*
G01X1315309Y68900D02*
X1315059Y69150D01*
G01X1317900Y68900D02*
X1315309D01*
G01X1262600Y126350D02*
X1257533D01*
G01X1266600D02*
X1262600D01*
G01X1253050D02*
X1257533D01*
G01X1253000Y126400D02*
X1253050Y126350D01*
G01X1271562Y126319D02*
X1288878D01*
G01X1271531Y126350D02*
X1271562Y126319D01*
G01X1266600Y126350D02*
X1271531D01*
G01X1256756Y156319D02*
X1288878D01*
G01X1334250Y109500D02*
Y104300D01*
G01Y109500D02*
Y113500D01*
G01Y115500D02*
Y113500D01*
G01X1333000Y116750D02*
X1334250Y115500D01*
G01X1333000Y120000D02*
Y116750D01*
G01X1253000Y132400D02*
X1256800D01*
G01X1330950Y256850D02*
Y348404D01*
G01X1364600Y223200D02*
X1330950Y256850D01*
G01X1332975Y258469D02*
Y349243D01*
G01X1378659Y212785D02*
X1332975Y258469D01*
G01X1330950Y348404D02*
X1294740Y384614D01*
G01X1262945Y377600D02*
Y383269D01*
G01X1332975Y349243D02*
X1296765Y385453D01*
G01X1265494Y472242D02*
Y479580D01*
G01X1272346Y465390D02*
X1265494Y472242D01*
G01X1448467Y465390D02*
X1272346D01*
G01X1277678Y403046D02*
Y417098D01*
G01Y403046D02*
Y396337D01*
G01X1294740Y384614D02*
Y402900D01*
G01X1262945Y383269D02*
Y389119D01*
G01X1271602Y448950D02*
X1560906D01*
G01X1253343Y467209D02*
X1271602Y448950D01*
G01X1253343Y474547D02*
Y467209D01*
G01X1296765Y385453D02*
Y403739D01*
G01X1257000Y434610D02*
X1248784Y442826D01*
G01X1257000Y434600D02*
Y434610D01*
G01X1249292Y465532D02*
Y472870D01*
G01X1269924Y444900D02*
X1249292Y465532D01*
G01X1323293Y444900D02*
X1269924D01*
G01X1338423Y429770D02*
X1323293Y444900D01*
G01X1338423Y429770D02*
X1356057Y412136D01*
G01X1273280Y453000D02*
X1630708D01*
G01X1257393Y468887D02*
X1273280Y453000D01*
G01X1257393Y476225D02*
Y468887D01*
G01X1259419Y469725D02*
Y477063D01*
G01X1273344Y455800D02*
X1259419Y469725D01*
G01X1664726Y455800D02*
X1273344D01*
G01X1263469Y471403D02*
Y478741D01*
G01X1274172Y460700D02*
X1263469Y471403D01*
G01X1573462Y460700D02*
X1274172D01*
G01X1272441Y450975D02*
X1626467D01*
G01X1255368Y468048D02*
X1272441Y450975D01*
G01X1255368Y475386D02*
Y468048D01*
G01X1327523Y467415D02*
X1344024Y483916D01*
G01X1273185Y467415D02*
X1327523D01*
G01X1267519Y473081D02*
X1273185Y467415D01*
G01X1267519Y480419D02*
Y473081D01*
G01X1277039Y458675D02*
X1662396D01*
G01X1277038Y458674D02*
X1277039Y458675D01*
G01X1274998Y458674D02*
X1277038D01*
G01X1274997Y458675D02*
X1274998Y458674D01*
G01X1273333Y458675D02*
X1274997D01*
G01X1261444Y470564D02*
X1273333Y458675D01*
G01X1261444Y477902D02*
Y470564D01*
G01X1247949Y423312D02*
Y423302D01*
G01X1270763Y446925D02*
X1443594D01*
G01X1251318Y466370D02*
X1270763Y446925D01*
G01X1251318Y473708D02*
Y466370D01*
G01X1245959Y435527D02*
X1245899D01*
G01X1246748Y498326D02*
Y587813D01*
G01X1265494Y479580D02*
X1246748Y498326D01*
G01X1311200Y517000D02*
X1317000D01*
G01X1321750D02*
X1317000D01*
G01X1322000Y517250D02*
X1321750Y517000D01*
G01X1322000Y508250D02*
X1317000D01*
G01D02*
X1312000D01*
G01D02*
X1307500D01*
G01X1300250D02*
X1307500D01*
G01X1298700Y509800D02*
X1300250Y508250D01*
G01X1298700Y515100D02*
Y509800D01*
G01X1300600Y517000D02*
X1298700Y515100D01*
G01X1303800Y517000D02*
X1300600D01*
G01X1322000Y504750D02*
X1325500D01*
G01X1306800Y515100D02*
Y525500D01*
G01X1306140Y514440D02*
X1306800Y515100D01*
G01X1303800Y514440D02*
X1306140D01*
G01X1306800Y529950D02*
X1306850Y530000D01*
G01X1306800Y525500D02*
Y529950D01*
G01X1306850Y535576D02*
Y534000D01*
G01X1308500Y537226D02*
X1306850Y535576D01*
G01X1308500Y539500D02*
Y537226D01*
G01X1306850Y530000D02*
Y534000D01*
G01X1329250Y533500D02*
X1324500D01*
G01X1315750Y520750D02*
X1322000D01*
G01X1314560Y519560D02*
X1315750Y520750D01*
G01X1311200Y519560D02*
X1314560D01*
G01X1322000Y520750D02*
X1326500D01*
G01Y524000D02*
X1323500Y527000D01*
G01X1326500Y520750D02*
Y524000D01*
G01X1323500Y532500D02*
X1324500Y533500D01*
G01X1323500Y527000D02*
Y532500D01*
G01X1332750Y527250D02*
Y533500D01*
G01X1332500Y527000D02*
X1332750Y527250D01*
G01X1338000Y559750D02*
X1335250Y562500D01*
G01X1338000Y535000D02*
Y559750D01*
G01X1336500Y533500D02*
X1338000Y535000D01*
G01X1335250Y569500D02*
Y566500D01*
G01X1333500Y571250D02*
X1335250Y569500D01*
G01Y562500D02*
Y566500D01*
G01X1332750Y533500D02*
X1336500D01*
G01X1249618Y498320D02*
X1267519Y480419D01*
G01X1249618Y587807D02*
Y498320D01*
G01X1252800Y585100D02*
Y588509D01*
G01X1256756Y609075D02*
X1288878D01*
G01X1266600Y579050D02*
X1262600D01*
G01D02*
X1257500D01*
G01X1252850D02*
X1257500D01*
G01X1252800Y579100D02*
X1252850Y579050D01*
G01X1267175Y579075D02*
X1288878D01*
G01X1267150Y579050D02*
X1267175Y579075D01*
G01X1266600Y579050D02*
X1267150D01*
G01X1333500Y573000D02*
Y571250D01*
G01X1247880Y652652D02*
X1266103Y670875D01*
G01X1247041Y654677D02*
X1266164Y673800D01*
G01X1251254Y648602D02*
X1269477Y666825D01*
G01X1271830Y664800D02*
X1253607Y646577D01*
G01X1802938Y664800D02*
X1271830D01*
G01X1250415Y650627D02*
X1268638Y668850D01*
G01X1266103Y670875D02*
X1428675D01*
G01X1330716Y679416D02*
Y856516D01*
G01X1325100Y673800D02*
X1330716Y679416D01*
G01X1266164Y673800D02*
X1325100D01*
G01X1269477Y666825D02*
X1663425D01*
G01X1259100Y680700D02*
Y852600D01*
G01X1268638Y668850D02*
X1565941D01*
G01X1330716Y856516D02*
X1335273Y861073D01*
G01X1259100Y852600D02*
X1255741Y855959D01*
G01X1709500Y900700D02*
X1269904D01*
G01X1268321Y898542D02*
X1746778D01*
G01X1334249Y923221D02*
X1605886D01*
G01X1327178Y916150D02*
X1334249Y923221D01*
G01X1271639Y916150D02*
X1327178D01*
G01X1246292Y941497D02*
X1271639Y916150D01*
G01X1246292Y1003513D02*
Y941497D01*
G01X1338701Y927271D02*
X1340324Y928894D01*
G01X1332571Y927271D02*
X1338701D01*
G01X1325500Y920200D02*
X1332571Y927271D01*
G01X1273317Y920200D02*
X1325500D01*
G01X1250343Y943174D02*
X1273317Y920200D01*
G01X1250343Y1005190D02*
Y943174D01*
G01X1325500Y907000D02*
X1272196D01*
G01X1572900Y902900D02*
X1270568D01*
G01X1335927Y919171D02*
X1764543D01*
G01X1333600Y916844D02*
X1335927Y919171D01*
G01X1333600Y916843D02*
Y916844D01*
G01X1328856Y912099D02*
X1333600Y916843D01*
G01X1269962Y912099D02*
X1328856D01*
G01X1333410Y925246D02*
X1467097D01*
G01X1326339Y918175D02*
X1333410Y925246D01*
G01X1272478Y918175D02*
X1326339D01*
G01X1248317Y942336D02*
X1272478Y918175D01*
G01X1248317Y1004352D02*
Y942336D01*
G01X1267802Y896197D02*
X1747297D01*
G01X1443992Y904962D02*
X1271370D01*
G01X1335273Y861073D02*
X1355142D01*
G01X1335088Y921196D02*
X1725917D01*
G01X1328017Y914125D02*
X1335088Y921196D01*
G01X1270800Y914125D02*
X1328017D01*
G01X1311200Y969500D02*
X1317000D01*
G01X1321750D02*
X1317000D01*
G01X1322000Y969750D02*
X1321750Y969500D01*
G01X1322000Y960750D02*
X1317000D01*
G01D02*
X1312000D01*
G01D02*
X1307500D01*
G01X1300250D02*
X1307500D01*
G01X1298500Y962500D02*
X1300250Y960750D01*
G01X1298500Y967900D02*
Y962500D01*
G01X1300100Y969500D02*
X1298500Y967900D01*
G01X1303800Y969500D02*
X1300100D01*
G01X1322000Y957250D02*
X1325500D01*
G01X1329250Y986000D02*
X1324500D01*
G01X1315750Y973250D02*
X1322000D01*
G01X1314560Y972060D02*
X1315750Y973250D01*
G01X1311200Y972060D02*
X1314560D01*
G01X1322000Y973250D02*
X1326500D01*
G01Y976500D02*
X1323500Y979500D01*
G01X1326500Y973250D02*
Y976500D01*
G01X1323500Y985000D02*
X1324500Y986000D01*
G01X1323500Y979500D02*
Y985000D01*
G01X1307850Y977800D02*
Y982200D01*
G01Y967850D02*
Y977800D01*
G01X1306940Y966940D02*
X1307850Y967850D01*
G01X1303800Y966940D02*
X1306940D01*
G01X1307850Y988850D02*
Y986200D01*
G01X1308500Y989500D02*
X1307850Y988850D01*
G01X1308500Y992000D02*
Y989500D01*
G01X1307850Y982200D02*
Y986200D01*
G01X1338000Y986500D02*
X1337500Y986000D01*
G01X1338000Y1012250D02*
Y986500D01*
G01X1335250Y1015000D02*
X1338000Y1012250D01*
G01X1337500Y986000D02*
X1332750D01*
G01X1335250Y1022000D02*
Y1019000D01*
G01X1333500Y1023750D02*
X1335250Y1022000D01*
G01X1333500Y1025500D02*
Y1023750D01*
G01X1335250Y1019000D02*
Y1015000D01*
G01X1332750Y979750D02*
Y986000D01*
G01X1332500Y979500D02*
X1332750Y979750D01*
G01X1262400Y1031750D02*
X1257100D01*
G01X1266400D02*
X1262400D01*
G01X1252850D02*
X1257100D01*
G01X1252800Y1031700D02*
X1252850Y1031750D01*
G01X1269700Y1031831D02*
X1288878D01*
G01X1269619Y1031750D02*
X1269700Y1031831D01*
G01X1266400Y1031750D02*
X1269619D01*
G01X1256756Y1061831D02*
X1288878D01*
G01X1288124Y1482250D02*
X1289574Y1483700D01*
G01X1288124Y1480000D02*
Y1482250D01*
G01X1334960Y1480000D02*
X1288124D01*
G01X1348031Y1466929D02*
X1334960Y1480000D01*
G01X1364600Y45500D02*
Y189600D01*
G01X1352900Y33800D02*
X1364600Y45500D01*
G01X1435200Y66560D02*
X1436560D01*
G01X1435200Y64000D02*
X1441000D01*
G01X1431300Y63300D02*
Y72150D01*
G01X1429440Y61440D02*
X1431300Y63300D01*
G01X1427800Y61440D02*
X1429440D01*
G01X1431300Y76050D02*
Y72150D01*
G01X1432250Y77000D02*
X1431300Y76050D01*
G01X1432250Y86250D02*
Y81000D01*
G01X1432500Y86500D02*
X1432250Y86250D01*
G01Y81000D02*
Y77000D01*
G01X1431500Y55250D02*
X1436000D01*
G01X1425250D02*
X1431500D01*
G01X1422900Y57600D02*
X1425250Y55250D01*
G01X1422900Y62500D02*
Y57600D01*
G01X1424400Y64000D02*
X1422900Y62500D01*
G01X1427800Y64000D02*
X1424400D01*
G01X1380969Y156319D02*
X1413091D01*
G01X1391200Y126350D02*
X1387200D01*
G01X1381756D02*
X1387200D01*
G01X1376750D02*
X1381756D01*
G01X1376700Y126400D02*
X1376750Y126350D01*
G01X1391231Y126319D02*
X1413091D01*
G01X1391200Y126350D02*
X1391231Y126319D01*
G01X1376700Y132400D02*
Y136000D01*
G01X1364600Y189600D02*
Y223200D01*
G01X1439819Y212785D02*
X1378659D01*
G01X1341324Y372244D02*
Y383426D01*
G01D02*
Y389276D01*
G01X1356057Y412136D02*
Y403203D01*
G01D02*
Y396494D01*
G01X1436000Y508250D02*
X1431500D01*
G01X1424250D02*
X1431500D01*
G01X1421700Y510800D02*
X1424250Y508250D01*
G01X1421700Y515300D02*
Y510800D01*
G01X1423400Y517000D02*
X1421700Y515300D01*
G01X1427800Y517000D02*
X1423400D01*
G01X1431350Y515150D02*
Y525000D01*
G01X1430640Y514440D02*
X1431350Y515150D01*
G01X1427800Y514440D02*
X1430640D01*
G01X1431350Y525000D02*
Y529900D01*
G01X1432500Y535050D02*
X1431350Y533900D01*
G01X1432500Y539500D02*
Y535050D01*
G01X1431350Y529900D02*
Y533900D01*
G01X1435200Y517000D02*
X1441000D01*
G01X1377100Y516992D02*
X1344024Y483916D01*
G01X1377100Y573200D02*
Y516992D01*
G01X1435200Y519560D02*
X1438560D01*
G01X1390400Y579050D02*
X1386400D01*
G01X1377100Y579200D02*
X1381600D01*
G01X1383957D02*
X1381600D01*
G01X1384107Y579050D02*
X1383957Y579200D01*
G01X1386400Y579050D02*
X1384107D01*
G01X1397291Y579075D02*
X1413091D01*
G01X1397266Y579050D02*
X1397291Y579075D01*
G01X1390400Y579050D02*
X1397266D01*
G01X1380969Y609075D02*
X1413091D01*
G01X1428675Y670875D02*
X1449000Y691200D01*
G01X1341324Y829350D02*
Y825000D01*
G01Y842032D02*
Y836182D01*
G01D02*
Y829350D01*
G01X1356057Y860158D02*
Y855959D01*
G01D02*
Y849250D01*
G01X1359197Y947767D02*
X1340324Y928894D01*
G01X1359197Y965000D02*
Y947767D01*
G01X1355142Y861073D02*
X1356057Y860158D01*
G01X1435200Y972060D02*
X1438560D01*
G01X1376900Y982703D02*
X1359197Y965000D01*
G01X1376900Y1025800D02*
Y982703D01*
G01X1391000Y1031850D02*
X1387000D01*
G01X1376900Y1031800D02*
X1381500D01*
G01X1384287D02*
X1381500D01*
G01X1384337Y1031850D02*
X1384287Y1031800D01*
G01X1387000Y1031850D02*
X1384337D01*
G01X1398482Y1031831D02*
X1413091D01*
G01X1398463Y1031850D02*
X1398482Y1031831D01*
G01X1391000Y1031850D02*
X1398463D01*
G01X1436000Y960750D02*
X1431500D01*
G01X1424850D02*
X1431500D01*
G01X1422300Y963300D02*
X1424850Y960750D01*
G01X1422300Y967000D02*
Y963300D01*
G01X1424800Y969500D02*
X1422300Y967000D01*
G01X1427800Y969500D02*
X1424800D01*
G01X1435200D02*
X1441000D01*
G01X1431350Y975050D02*
Y978200D01*
G01X1431600Y974800D02*
X1431350Y975050D01*
G01X1431600Y968400D02*
Y974800D01*
G01X1430140Y966940D02*
X1431600Y968400D01*
G01X1427800Y966940D02*
X1430140D01*
G01X1431350Y978200D02*
Y982400D01*
G01X1432500Y987550D02*
X1431350Y986400D01*
G01X1432500Y992000D02*
Y987550D01*
G01X1431350Y982400D02*
Y986400D01*
G01X1380969Y1061831D02*
X1413091D01*
G01X1438200Y68200D02*
X1441200D01*
G01X1436560Y66560D02*
X1438200Y68200D01*
G01X1443300D02*
X1441200D01*
G01X1443750Y67750D02*
X1443300Y68200D01*
G01X1446000Y67750D02*
X1443750D01*
G01X1450500Y71000D02*
X1447500Y74000D01*
G01X1450500Y67750D02*
Y71000D01*
G01Y67750D02*
X1446000D01*
G01X1451200Y80500D02*
X1453250D01*
G01X1447500Y76800D02*
X1451200Y80500D01*
G01X1447500Y74000D02*
Y76800D01*
G01X1456750Y74250D02*
Y80500D01*
G01X1456500Y74000D02*
X1456750Y74250D01*
G01X1462000Y82000D02*
Y106750D01*
G01X1460500Y80500D02*
X1462000Y82000D01*
G01X1456750Y80500D02*
X1460500D01*
G01X1445750Y64000D02*
X1441000D01*
G01X1446000Y64250D02*
X1445750Y64000D01*
G01X1464025Y66275D02*
Y188579D01*
G01X1449500Y51750D02*
X1464025Y66275D01*
G01X1446000Y51750D02*
X1449500D01*
G01X1446000Y55250D02*
X1441000D01*
G01X1436000D02*
X1441000D01*
G01X1462000Y106750D02*
X1459250Y109500D01*
G01Y116500D02*
Y113500D01*
G01X1457500Y118250D02*
X1459250Y116500D01*
G01X1457500Y120000D02*
Y118250D01*
G01X1459250Y109500D02*
Y113500D01*
G01X1515400Y126350D02*
X1511400D01*
G01X1505968D02*
X1511400D01*
G01X1501350D02*
X1505968D01*
G01X1501300Y126400D02*
X1501350Y126350D01*
G01X1515431Y126319D02*
X1537303D01*
G01X1515400Y126350D02*
X1515431Y126319D01*
G01X1464025Y188579D02*
X1453052Y199552D01*
G01X1505181Y156319D02*
X1537303D01*
G01X1501300Y136100D02*
Y132400D01*
G01X1453052Y199552D02*
X1439819Y212785D01*
G01X1465536Y372244D02*
Y383426D01*
G01X1465195Y482118D02*
X1448467Y465390D01*
G01X1465536Y383426D02*
Y389276D01*
G01X1443594Y446925D02*
X1462350Y428169D01*
G01X1480269Y410250D02*
Y403203D01*
G01X1462350Y428169D02*
X1480269Y410250D01*
G01Y403203D02*
Y396494D01*
G01X1500800Y517723D02*
X1465195Y482118D01*
G01X1500800Y572800D02*
Y517723D01*
G01X1456750Y527250D02*
Y533500D01*
G01X1456500Y527000D02*
X1456750Y527250D01*
G01X1462000Y559750D02*
X1459250Y562500D01*
G01X1462000Y535000D02*
Y559750D01*
G01X1460500Y533500D02*
X1462000Y535000D01*
G01X1459250Y569500D02*
Y566500D01*
G01X1457500Y571250D02*
X1459250Y569500D01*
G01Y562500D02*
Y566500D01*
G01X1456750Y533500D02*
X1460500D01*
G01X1446000Y508250D02*
X1441000D01*
G01D02*
X1436000D01*
G01X1446000Y504750D02*
X1449500D01*
G01X1445750Y517000D02*
X1441000D01*
G01X1446000Y517250D02*
X1445750Y517000D01*
G01X1453250Y533500D02*
X1448500D01*
G01X1439750Y520750D02*
X1446000D01*
G01X1438560Y519560D02*
X1439750Y520750D01*
G01X1446000D02*
X1450500D01*
G01Y524000D02*
X1447500Y527000D01*
G01X1450500Y520750D02*
Y524000D01*
G01X1447500Y532500D02*
X1448500Y533500D01*
G01X1447500Y527000D02*
Y532500D01*
G01X1457500Y573000D02*
Y571250D01*
G01X1500800Y578800D02*
X1505900D01*
G01X1515200Y579050D02*
X1511200D01*
G01X1508837Y578800D02*
X1505900D01*
G01X1509087Y579050D02*
X1508837Y578800D01*
G01X1511200Y579050D02*
X1509087D01*
G01X1520029Y579075D02*
X1537303D01*
G01X1520004Y579050D02*
X1520029Y579075D01*
G01X1515200Y579050D02*
X1520004D01*
G01X1505181Y609075D02*
X1537303D01*
G01X1449000Y691200D02*
Y852500D01*
G01X1465536Y829350D02*
Y825000D01*
G01Y842032D02*
Y836182D01*
G01D02*
Y829350D01*
G01X1480269Y858125D02*
Y855959D01*
G01X1449000Y852500D02*
X1457133Y860633D01*
G01X1480269Y855959D02*
Y849250D01*
G01X1467097Y925246D02*
X1472646Y930795D01*
G01X1484414Y942563D02*
X1472646Y930795D01*
G01X1484414Y990900D02*
Y942563D01*
G01X1477761Y860633D02*
X1480269Y858125D01*
G01X1457133Y860633D02*
X1477761D01*
G01X1462000Y986500D02*
X1461500Y986000D01*
G01X1462000Y1012250D02*
Y986500D01*
G01X1459250Y1015000D02*
X1462000Y1012250D01*
G01X1456750Y979750D02*
Y986000D01*
G01X1456500Y979500D02*
X1456750Y979750D01*
G01X1459250Y1022000D02*
Y1019000D01*
G01X1457500Y1023750D02*
X1459250Y1022000D01*
G01X1457500Y1025500D02*
Y1023750D01*
G01X1459250Y1019000D02*
Y1015000D01*
G01X1456750Y986000D02*
X1461500D01*
G01X1453250D02*
X1448500D01*
G01X1439750Y973250D02*
X1446000D01*
G01X1438560Y972060D02*
X1439750Y973250D01*
G01X1446000D02*
X1450500D01*
G01Y976500D02*
X1447500Y979500D01*
G01X1450500Y973250D02*
Y976500D01*
G01X1447500Y985000D02*
X1448500Y986000D01*
G01X1447500Y979500D02*
Y985000D01*
G01X1515400Y1031850D02*
X1511400D01*
G01D02*
X1505700D01*
G01X1505650Y1031800D02*
X1505700Y1031850D01*
G01X1500700Y1031800D02*
X1505650D01*
G01X1515419Y1031831D02*
X1537303D01*
G01X1515400Y1031850D02*
X1515419Y1031831D01*
G01X1500700Y1007186D02*
X1484414Y990900D01*
G01X1500700Y1025800D02*
Y1007186D01*
G01X1446000Y960750D02*
X1441000D01*
G01D02*
X1436000D01*
G01X1447850Y957250D02*
X1450100Y959500D01*
G01X1446000Y957250D02*
X1447850D01*
G01X1445750Y969500D02*
X1441000D01*
G01X1446000Y969750D02*
X1445750Y969500D01*
G01X1505181Y1061831D02*
X1537303D01*
G01X1555450Y57650D02*
Y59500D01*
G01X1553200Y55400D02*
X1555450Y57650D01*
G01X1553200Y49100D02*
Y55400D01*
G01X1552040Y47940D02*
X1553200Y49100D01*
G01X1549300Y47940D02*
X1552040D01*
G01X1555450Y59500D02*
Y63300D01*
G01X1551450Y73300D02*
X1555450Y69300D01*
G01X1546700Y73300D02*
X1551450D01*
G01X1545000Y75000D02*
X1546700Y73300D01*
G01X1545000Y95900D02*
Y75000D01*
G01X1555450Y63300D02*
Y69300D01*
G01X1556700Y50500D02*
X1562500D01*
G01X1567250D02*
X1562500D01*
G01X1567500Y50750D02*
X1567250Y50500D01*
G01X1546400D02*
X1549300D01*
G01X1545100Y49200D02*
X1546400Y50500D01*
G01X1545100Y42600D02*
Y49200D01*
G01X1545950Y41750D02*
X1545100Y42600D01*
G01X1553000Y41750D02*
X1545950D01*
G01X1567500D02*
X1562500D01*
G01D02*
X1557500D01*
G01D02*
X1553000D01*
G01X1576800Y69000D02*
X1570000D01*
G01X1598886D02*
X1576800D01*
G01X1614075Y84189D02*
X1598886Y69000D01*
G01X1614075Y123325D02*
Y84189D01*
G01X1569750Y69250D02*
X1563500D01*
G01X1570000Y69000D02*
X1569750Y69250D01*
G01X1571000Y38250D02*
X1567500D01*
G01X1616100Y83350D02*
X1571000Y38250D01*
G01X1616100Y203786D02*
Y83350D01*
G01X1563500Y65750D02*
Y61000D01*
G01X1561250Y54250D02*
X1567500D01*
G01X1560060Y53060D02*
X1561250Y54250D01*
G01X1556700Y53060D02*
X1560060D01*
G01X1567500Y54250D02*
X1572000D01*
G01X1570000Y59000D02*
Y60000D01*
G01X1572000Y57000D02*
X1570000Y59000D01*
G01X1572000Y54250D02*
Y57000D01*
G01X1564500Y60000D02*
X1563500Y61000D01*
G01X1570000Y60000D02*
X1564500D01*
G01X1549000Y99900D02*
X1545000Y95900D01*
G01X1549000Y102000D02*
Y99900D01*
G01X1604650Y134250D02*
Y133000D01*
G01X1597900Y141000D02*
X1604650Y134250D01*
G01X1590400Y141000D02*
X1597900D01*
G01X1604650Y133000D02*
Y129000D01*
G01X1608400D02*
X1614075Y123325D01*
G01X1604650Y129000D02*
X1608400D01*
G01X1625300Y126400D02*
X1630131D01*
G01X1625300Y136000D02*
Y132400D01*
G01X1589749Y372244D02*
Y383426D01*
G01X1560906Y448950D02*
X1578333Y431523D01*
G01X1604482Y405374D02*
Y403203D01*
G01X1578333Y431523D02*
X1604482Y405374D01*
G01Y403203D02*
Y396494D01*
G01X1587023Y474261D02*
X1573462Y460700D01*
G01X1625500Y512738D02*
X1587023Y474261D01*
G01X1589749Y383426D02*
Y389276D01*
G01X1577750Y533500D02*
X1573000D01*
G01X1564250Y520750D02*
X1570500D01*
G01X1563060Y519560D02*
X1564250Y520750D01*
G01X1559700Y519560D02*
X1563060D01*
G01X1570500Y520750D02*
X1575000D01*
G01Y524000D02*
X1572000Y527000D01*
G01X1575000Y520750D02*
Y524000D01*
G01X1572000Y532500D02*
X1573000Y533500D01*
G01X1572000Y527000D02*
Y532500D01*
G01X1559700Y517000D02*
X1565500D01*
G01X1570250D02*
X1565500D01*
G01X1570500Y517250D02*
X1570250Y517000D01*
G01X1625500Y573000D02*
Y512738D01*
G01X1570500Y508250D02*
X1565500D01*
G01D02*
X1560500D01*
G01D02*
X1556000D01*
G01X1548350D02*
X1556000D01*
G01X1547000Y509600D02*
X1548350Y508250D01*
G01X1547000Y514900D02*
Y509600D01*
G01X1549100Y517000D02*
X1547000Y514900D01*
G01X1552300Y517000D02*
X1549100D01*
G01X1555450Y515050D02*
Y524900D01*
G01X1554840Y514440D02*
X1555450Y515050D01*
G01X1552300Y514440D02*
X1554840D01*
G01X1555450Y524900D02*
Y529800D01*
G01X1557000Y535350D02*
X1555450Y533800D01*
G01X1557000Y539500D02*
Y535350D01*
G01X1555450Y529800D02*
Y533800D01*
G01X1581250Y527250D02*
Y533500D01*
G01X1581000Y527000D02*
X1581250Y527250D01*
G01X1586500Y559750D02*
X1583750Y562500D01*
G01X1586500Y535000D02*
Y559750D01*
G01X1585000Y533500D02*
X1586500Y535000D01*
G01X1583750Y569500D02*
Y566500D01*
G01X1582000Y571250D02*
X1583750Y569500D01*
G01Y562500D02*
Y566500D01*
G01X1581250Y533500D02*
X1585000D01*
G01X1570500Y504750D02*
X1574000D01*
G01X1625500Y579000D02*
X1630050D01*
G01X1582000Y573000D02*
Y571250D01*
G01X1583300Y686209D02*
Y818800D01*
G01X1565941Y668850D02*
X1583300Y686209D01*
G01X1589749Y826651D02*
X1591400Y825000D01*
G01X1589749Y829350D02*
Y826651D01*
G01Y842032D02*
Y836182D01*
G01D02*
Y829350D01*
G01X1604482Y858400D02*
Y855959D01*
G01X1578489Y855012D02*
X1583977Y860500D01*
G01X1578489Y823611D02*
Y855012D01*
G01X1583300Y818800D02*
X1578489Y823611D01*
G01X1604482Y855959D02*
Y849250D01*
G01X1605886Y923221D02*
X1607884Y925219D01*
G01X1618000Y935335D02*
X1607884Y925219D01*
G01X1618000Y1006400D02*
Y935335D01*
G01X1602382Y860500D02*
X1604482Y858400D01*
G01X1583977Y860500D02*
X1602382D01*
G01X1559700Y969500D02*
X1565500D01*
G01X1570250D02*
X1565500D01*
G01X1570500Y969750D02*
X1570250Y969500D01*
G01X1625400Y1013800D02*
X1618000Y1006400D01*
G01X1625400Y1025900D02*
Y1013800D01*
G01X1570500Y960750D02*
X1565500D01*
G01D02*
X1560500D01*
G01D02*
X1556000D01*
G01X1548250D02*
X1556000D01*
G01X1546800Y962200D02*
X1548250Y960750D01*
G01X1546800Y967600D02*
Y962200D01*
G01X1548700Y969500D02*
X1546800Y967600D01*
G01X1552300Y969500D02*
X1548700D01*
G01X1570500Y957250D02*
X1574000D01*
G01X1586500Y986500D02*
X1586000Y986000D01*
G01X1586500Y1011000D02*
Y986500D01*
G01X1583750Y1013750D02*
X1586500Y1011000D01*
G01X1583750Y1015000D02*
Y1013750D01*
G01X1581250Y979750D02*
Y986000D01*
G01X1581000Y979500D02*
X1581250Y979750D01*
G01X1583750Y1022000D02*
Y1019000D01*
G01X1582000Y1023750D02*
X1583750Y1022000D01*
G01X1582000Y1025500D02*
Y1023750D01*
G01X1583750Y1019000D02*
Y1015000D01*
G01X1581250Y986000D02*
X1586000D01*
G01X1625450Y1031850D02*
X1629800D01*
G01X1625400Y1031900D02*
X1625450Y1031850D01*
G01X1555750Y978600D02*
Y982600D01*
G01Y967850D02*
Y978600D01*
G01X1554840Y966940D02*
X1555750Y967850D01*
G01X1552300Y966940D02*
X1554840D01*
G01X1557000Y987850D02*
X1555750Y986600D01*
G01X1557000Y992000D02*
Y987850D01*
G01X1555750Y982600D02*
Y986600D01*
G01X1577750Y986000D02*
X1573000D01*
G01X1564250Y973250D02*
X1570500D01*
G01X1563060Y972060D02*
X1564250Y973250D01*
G01X1559700Y972060D02*
X1563060D01*
G01X1570500Y973250D02*
X1575000D01*
G01Y976500D02*
X1572000Y979500D01*
G01X1575000Y973250D02*
Y976500D01*
G01X1572000Y985000D02*
X1573000Y986000D01*
G01X1572000Y979500D02*
Y985000D01*
G01X1694500Y55250D02*
X1689500D01*
G01X1680000D02*
X1684500D01*
G01D02*
X1689500D01*
G01X1673950D02*
X1680000D01*
G01X1671300Y57900D02*
X1673950Y55250D01*
G01X1671300Y62000D02*
Y57900D01*
G01X1673300Y64000D02*
X1671300Y62000D01*
G01X1676300Y64000D02*
X1673300D01*
G01X1683700D02*
X1689500D01*
G01X1694250D02*
X1689500D01*
G01X1694500Y64250D02*
X1694250Y64000D01*
G01X1701750Y80500D02*
X1697000D01*
G01X1688250Y67750D02*
X1694500D01*
G01X1687060Y66560D02*
X1688250Y67750D01*
G01X1683700Y66560D02*
X1687060D01*
G01X1694500Y67750D02*
X1699000D01*
G01Y71000D02*
X1696000Y74000D01*
G01X1699000Y67750D02*
Y71000D01*
G01X1696000Y79500D02*
X1697000Y80500D01*
G01X1696000Y74000D02*
Y79500D01*
G01X1705250Y74250D02*
Y80500D01*
G01X1705000Y74000D02*
X1705250Y74250D01*
G01X1710500Y82000D02*
Y106750D01*
G01X1709000Y80500D02*
X1710500Y82000D01*
G01X1705250Y80500D02*
X1709000D01*
G01X1702470Y51750D02*
X1694500D01*
G01X1712525Y61805D02*
X1702470Y51750D01*
G01X1712525Y191268D02*
Y61805D01*
G01X1679600Y63100D02*
Y72500D01*
G01X1677940Y61440D02*
X1679600Y63100D01*
G01X1676300Y61440D02*
X1677940D01*
G01X1679600Y76950D02*
X1679650Y77000D01*
G01X1679600Y72500D02*
Y76950D01*
G01X1679650Y77000D02*
Y81000D01*
G01X1681000Y82350D02*
Y86500D01*
G01X1679650Y81000D02*
X1681000Y82350D01*
G01X1710500Y106750D02*
X1707750Y109500D01*
G01Y116500D02*
Y113500D01*
G01X1706000Y118250D02*
X1707750Y116500D01*
G01X1706000Y120000D02*
Y118250D01*
G01X1707750Y109500D02*
Y113500D01*
G01X1629394Y156319D02*
X1661516D01*
G01X1639300Y126350D02*
X1635300D01*
G01D02*
X1630181D01*
G01X1630131Y126400D02*
X1630181Y126350D01*
G01X1642753Y126319D02*
X1661516D01*
G01X1642722Y126350D02*
X1642753Y126319D01*
G01X1639300Y126350D02*
X1642722D01*
G01X1667837Y415871D02*
X1779110D01*
G01X1630708Y453000D02*
X1667837Y415871D01*
G01X1697288Y488362D02*
X1664726Y455800D01*
G01X1721299Y411514D02*
X1721381Y411596D01*
G01X1665928Y411514D02*
X1721299D01*
G01X1626467Y450975D02*
X1665928Y411514D01*
G01X1721381Y411596D02*
X1763114D01*
G01X1662396Y458675D02*
X1701720Y497999D01*
G01X1705250Y527250D02*
Y533500D01*
G01X1705000Y527000D02*
X1705250Y527250D01*
G01X1710500Y559750D02*
X1707750Y562500D01*
G01X1710500Y535000D02*
Y559750D01*
G01X1709000Y533500D02*
X1710500Y535000D01*
G01X1707750Y569500D02*
Y566500D01*
G01X1706000Y571250D02*
X1707750Y569500D01*
G01Y562500D02*
Y566500D01*
G01X1705250Y533500D02*
X1709000D01*
G01X1683700Y517000D02*
X1689500D01*
G01X1694250D02*
X1689500D01*
G01X1694500Y517250D02*
X1694250Y517000D01*
G01X1680050Y515350D02*
Y525200D01*
G01X1679140Y514440D02*
X1680050Y515350D01*
G01X1676300Y514440D02*
X1679140D01*
G01X1680050Y525200D02*
Y530100D01*
G01X1681000Y535050D02*
X1680050Y534100D01*
G01X1681000Y539500D02*
Y535050D01*
G01X1680050Y530100D02*
Y534100D01*
G01X1758173Y488362D02*
X1697288D01*
G01X1694500Y508250D02*
X1689500D01*
G01D02*
X1684500D01*
G01D02*
X1680000D01*
G01X1672650D02*
X1680000D01*
G01X1671400Y509500D02*
X1672650Y508250D01*
G01X1671400Y515600D02*
Y509500D01*
G01X1672800Y517000D02*
X1671400Y515600D01*
G01X1676300Y517000D02*
X1672800D01*
G01X1701750Y533500D02*
X1697000D01*
G01X1688250Y520750D02*
X1694500D01*
G01X1687060Y519560D02*
X1688250Y520750D01*
G01X1683700Y519560D02*
X1687060D01*
G01X1694500Y520750D02*
X1699000D01*
G01Y524000D02*
X1696000Y527000D01*
G01X1699000Y520750D02*
Y524000D01*
G01X1696000Y532500D02*
X1697000Y533500D01*
G01X1696000Y527000D02*
Y532500D01*
G01X1748524Y544803D02*
X1701720Y497999D01*
G01X1694500Y504750D02*
X1698000D01*
G01X1706000Y573000D02*
Y571250D01*
G01X1629394Y609075D02*
X1661516D01*
G01X1638200Y579050D02*
X1634200D01*
G01D02*
X1630100D01*
G01X1630050Y579000D02*
X1630100Y579050D01*
G01X1645858Y579075D02*
X1661516D01*
G01X1645833Y579050D02*
X1645858Y579075D01*
G01X1638200Y579050D02*
X1645833D01*
G01X1672200Y675600D02*
Y820333D01*
G01X1663425Y666825D02*
X1672200Y675600D01*
G01X1713961Y829350D02*
Y825000D01*
G01Y842032D02*
Y836182D01*
G01D02*
Y829350D01*
G01X1672200Y820333D02*
X1712280Y860413D01*
G01D02*
X1727525D01*
G01X1694500Y960750D02*
X1689500D01*
G01D02*
X1684500D01*
G01D02*
X1680000D01*
G01X1673450D02*
X1680000D01*
G01X1671200Y963000D02*
X1673450Y960750D01*
G01X1671200Y967900D02*
Y963000D01*
G01X1672800Y969500D02*
X1671200Y967900D01*
G01X1676300Y969500D02*
X1672800D01*
G01X1694500Y957250D02*
X1698000D01*
G01X1683700Y969500D02*
X1689500D01*
G01X1694250D02*
X1689500D01*
G01X1694500Y969750D02*
X1694250Y969500D01*
G01X1679650Y967750D02*
Y978000D01*
G01X1678840Y966940D02*
X1679650Y967750D01*
G01X1676300Y966940D02*
X1678840D01*
G01X1679650Y978000D02*
Y982300D01*
G01X1681000Y987650D02*
X1679650Y986300D01*
G01X1681000Y992000D02*
Y987650D01*
G01X1679650Y982300D02*
Y986300D01*
G01X1639100Y1031850D02*
X1635100D01*
G01X1629800D02*
X1635100D01*
G01X1643349Y1031831D02*
X1661516D01*
G01X1643330Y1031850D02*
X1643349Y1031831D01*
G01X1639100Y1031850D02*
X1643330D01*
G01X1705250Y983250D02*
Y986000D01*
G01X1705000Y983000D02*
X1705250Y983250D01*
G01X1705000Y979500D02*
Y983000D01*
G01X1710500Y1012250D02*
X1707750Y1015000D01*
G01X1710500Y987500D02*
Y1012250D01*
G01X1709000Y986000D02*
X1710500Y987500D01*
G01X1707750Y1022000D02*
Y1019000D01*
G01X1706000Y1023750D02*
X1707750Y1022000D01*
G01X1706000Y1025500D02*
Y1023750D01*
G01X1707750Y1015000D02*
Y1019000D01*
G01X1705250Y986000D02*
X1709000D01*
G01X1701750D02*
X1697000D01*
G01X1688250Y973250D02*
X1694500D01*
G01X1687060Y972060D02*
X1688250Y973250D01*
G01X1683700Y972060D02*
X1687060D01*
G01X1694500Y973250D02*
X1699000D01*
G01Y976500D02*
X1696000Y979500D01*
G01X1699000Y973250D02*
Y976500D01*
G01X1696000Y985000D02*
X1697000Y986000D01*
G01X1696000Y979500D02*
Y985000D01*
G01X1629394Y1061831D02*
X1661516D01*
G01X1715275Y1480000D02*
X1728346Y1466929D01*
G01X1667500Y1480000D02*
X1715275D01*
G01X1656250Y1468750D02*
X1667500Y1480000D01*
G01X1656250Y1465000D02*
Y1468750D01*
G01Y1465000D02*
Y1461250D01*
G01X1803900Y17700D02*
X1811800D01*
G01X1802461Y19139D02*
X1803900Y17700D01*
G01X1802461Y23406D02*
Y19139D01*
G01X1815400Y17700D02*
X1811800D01*
G01X1817816Y20116D02*
X1815400Y17700D01*
G01X1810800Y38200D02*
X1812800D01*
G01X1808100Y35500D02*
X1810800Y38200D01*
G01X1801200Y35500D02*
X1808100D01*
G01X1799901Y36799D02*
X1801200Y35500D01*
G01X1799901Y39586D02*
Y36799D01*
G01X1803660Y70140D02*
X1803200Y70600D01*
G01X1808600Y70140D02*
X1803660D01*
G01X1803650Y74500D02*
X1803100Y75050D01*
G01X1803650Y73200D02*
Y74500D01*
G01X1803200Y72750D02*
X1803650Y73200D01*
G01X1803200Y70600D02*
Y72750D01*
G01X1795750Y75050D02*
X1799100D01*
G01X1792000Y78800D02*
X1795750Y75050D01*
G01X1792000Y96000D02*
Y78800D01*
G01X1799100Y75050D02*
X1803100D01*
G01X1816000Y72700D02*
X1818400D01*
G01X1804700Y63200D02*
X1804800Y63100D01*
G01X1801150Y63200D02*
X1804700D01*
G01X1806150Y64450D02*
X1808500D01*
G01X1804800Y63100D02*
X1806150Y64450D01*
G01X1812750Y71350D02*
Y64400D01*
G01X1811400Y72700D02*
X1812750Y71350D01*
G01X1808600Y72700D02*
X1811400D01*
G01X1812700Y64450D02*
X1812750Y64400D01*
G01X1808500Y64450D02*
X1812700D01*
G01X1818200Y64400D02*
X1816250D01*
G01X1816000Y78011D02*
X1818928Y80939D01*
G01X1816000Y75260D02*
Y78011D01*
G01X1802761Y12975D02*
X1823975D01*
G01X1797341Y18395D02*
X1802761Y12975D01*
G01X1797341Y23406D02*
Y18395D01*
G01X1815564Y15000D02*
X1819841Y19277D01*
G01X1803600Y15000D02*
X1815564D01*
G01X1799901Y18699D02*
X1803600Y15000D01*
G01X1799901Y23406D02*
Y18699D01*
G01X1796300Y100300D02*
X1792000Y96000D01*
G01X1796300Y111100D02*
Y100300D01*
G01X1754300Y125900D02*
X1749700D01*
G01X1763600Y126350D02*
X1759600D01*
G01X1756784Y125900D02*
X1754300D01*
G01X1757234Y126350D02*
X1756784Y125900D01*
G01X1759600Y126350D02*
X1757234D01*
G01X1769407Y126319D02*
X1785728D01*
G01X1769376Y126350D02*
X1769407Y126319D01*
G01X1763600Y126350D02*
X1769376D01*
G01X1749700Y131900D02*
Y135600D01*
G01X1753606Y156319D02*
X1785728D01*
G01X1805142Y383782D02*
Y372600D01*
G01X1753442Y405641D02*
X1753631Y405830D01*
G01X1753442Y402630D02*
Y405641D01*
G01X1753509Y402563D02*
X1753442Y402630D01*
G01X1753509Y396293D02*
Y402563D01*
G01X1786466Y408545D02*
X1817343D01*
G01X1786451Y408530D02*
X1786466Y408545D01*
G01X1779110Y415871D02*
X1786451Y408530D01*
G01X1764599Y473245D02*
Y481936D01*
G01X1767041Y470803D02*
X1764599Y473245D01*
G01X1805248Y470803D02*
X1767041D01*
G01X1815554Y481109D02*
X1805248Y470803D01*
G01X1767666Y402286D02*
X1767651Y402301D01*
G01X1767666Y396297D02*
Y402286D01*
G01X1767651Y407059D02*
Y402301D01*
G01X1763114Y411596D02*
X1767651Y407059D01*
G01X1805142Y389632D02*
Y383782D01*
G01X1807700Y517000D02*
X1813500D01*
G01X1818250D02*
X1813500D01*
G01X1764599Y481936D02*
X1758173Y488362D01*
G01X1843241Y481109D02*
X1815554D01*
G01X1812250Y520750D02*
X1818500D01*
G01X1811060Y519560D02*
X1812250Y520750D01*
G01X1807700Y519560D02*
X1811060D01*
G01X1804050Y516350D02*
Y525100D01*
G01X1802140Y514440D02*
X1804050Y516350D01*
G01X1800300Y514440D02*
X1802140D01*
G01X1804050Y525100D02*
Y530100D01*
G01X1805000Y535050D02*
X1804050Y534100D01*
G01X1805000Y539500D02*
Y535050D01*
G01X1804050Y530100D02*
Y534100D01*
G01X1748524Y590816D02*
Y544803D01*
G01X1818500Y508250D02*
X1813500D01*
G01D02*
X1808500D01*
G01D02*
X1804000D01*
G01X1798150D02*
X1804000D01*
G01X1795500Y510900D02*
X1798150Y508250D01*
G01X1795500Y515400D02*
Y510900D01*
G01X1797100Y517000D02*
X1795500Y515400D01*
G01X1800300Y517000D02*
X1797100D01*
G01X1763000Y595000D02*
Y589000D01*
G01X1763250Y579500D02*
Y583500D01*
G01X1763675Y579075D02*
X1785728D01*
G01X1763250Y579500D02*
X1763675Y579075D01*
G01X1763250Y588750D02*
X1763000Y589000D01*
G01X1763250Y583500D02*
Y588750D01*
G01X1753606Y609075D02*
X1785728D01*
G01X1752708Y595000D02*
X1748524Y590816D01*
G01X1757000Y595000D02*
X1752708D01*
G01X1827214Y689076D02*
X1802938Y664800D01*
G01X1728694Y859244D02*
Y855959D01*
G01D02*
Y849250D01*
G01X1803425Y923325D02*
X1820700Y940600D01*
G01X1771561Y923325D02*
X1803425D01*
G01X1746778Y898542D02*
X1771561Y923325D01*
G01X1814500Y943500D02*
X1861278D01*
G01X1796350Y925350D02*
X1814500Y943500D01*
G01X1770722Y925350D02*
X1796350D01*
G01X1764543Y919171D02*
X1770722Y925350D01*
G01X1808800Y921300D02*
X1827700Y940200D01*
G01X1772400Y921300D02*
X1808800D01*
G01X1747297Y896197D02*
X1772400Y921300D01*
G01X1727525Y860413D02*
X1728694Y859244D01*
G01X1725917Y921196D02*
X1726771Y922050D01*
G01X1735500Y930779D02*
X1726771Y922050D01*
G01X1735500Y983100D02*
Y930779D01*
G01X1763300Y1031850D02*
X1759300D01*
G01X1754300D02*
X1759300D01*
G01X1754250Y1031900D02*
X1754300Y1031850D01*
G01X1749300Y1031900D02*
X1754250D01*
G01X1764000Y1031831D02*
X1785728D01*
G01X1763981Y1031850D02*
X1764000Y1031831D01*
G01X1763300Y1031850D02*
X1763981D01*
G01X1803750Y978100D02*
Y982200D01*
G01Y967750D02*
Y978100D01*
G01X1802940Y966940D02*
X1803750Y967750D01*
G01X1800300Y966940D02*
X1802940D01*
G01X1805000Y987450D02*
X1803750Y986200D01*
G01X1805000Y992000D02*
Y987450D01*
G01X1803750Y982200D02*
Y986200D01*
G01X1818500Y960750D02*
X1813500D01*
G01D02*
X1808500D01*
G01D02*
X1804000D01*
G01X1796650D02*
X1804000D01*
G01X1795200Y962200D02*
X1796650Y960750D01*
G01X1795200Y967900D02*
Y962200D01*
G01X1796800Y969500D02*
X1795200Y967900D01*
G01X1800300Y969500D02*
X1796800D01*
G01X1807700D02*
X1813500D01*
G01X1818250D02*
X1813500D01*
G01X1812250Y973250D02*
X1818500D01*
G01X1811060Y972060D02*
X1812250Y973250D01*
G01X1807700Y972060D02*
X1811060D01*
G01X1749300Y996900D02*
X1735500Y983100D01*
G01X1749300Y1025900D02*
Y996900D01*
G01X1753606Y1061831D02*
X1785728D01*
G01X1832250Y32000D02*
X1825350D01*
G01X1834950Y29300D02*
X1832250Y32000D01*
G01X1817816Y25016D02*
Y20116D01*
G01X1822600Y29800D02*
X1817816Y25016D01*
G01X1823150Y29800D02*
X1822600D01*
G01X1825350Y32000D02*
X1823150Y29800D01*
G01X1874500Y72720D02*
Y73700D01*
G01X1878298Y68922D02*
X1874500Y72720D01*
G01Y73750D02*
X1878250Y77500D01*
G01X1874500Y73700D02*
Y73750D01*
G01X1885000Y86375D02*
Y111500D01*
G01X1882966Y84341D02*
X1885000Y86375D01*
G01X1879741Y84341D02*
X1882966D01*
G01X1878250Y82850D02*
X1879741Y84341D01*
G01X1878250Y81500D02*
Y82850D01*
G01Y77500D02*
Y81500D01*
G01X1882250Y19000D02*
X1878700D01*
G01X1886060Y22810D02*
X1882250Y19000D01*
G01X1886060Y29300D02*
Y22810D01*
G01X1877650Y19000D02*
X1874900Y21750D01*
G01X1878700Y19000D02*
X1877650D01*
G01X1862550Y26300D02*
Y22300D01*
G01X1862300Y26550D02*
X1862550Y26300D01*
G01Y22300D02*
X1868800D01*
G01X1874350D02*
X1874900Y21750D01*
G01X1868800Y22300D02*
X1874350D01*
G01X1872900Y42250D02*
X1876700D01*
G01X1884600Y40500D02*
Y42250D01*
G01X1883500Y39400D02*
X1884600Y40500D01*
G01X1883500Y36700D02*
Y39400D01*
G01X1876700Y42250D02*
X1880500D01*
G01X1884600D02*
X1880500D01*
G01X1862750Y70450D02*
Y73500D01*
G01X1870200Y63000D02*
X1862750Y70450D01*
G01X1870200Y37800D02*
Y63000D01*
G01X1871300Y36700D02*
X1870200Y37800D01*
G01X1880940Y36700D02*
X1871300D01*
G01X1862750Y73500D02*
Y78000D01*
G01X1861000Y83750D02*
X1862750Y82000D01*
G01X1861000Y110000D02*
Y83750D01*
G01X1862750Y78000D02*
Y82000D01*
G01X1822428Y80939D02*
Y77200D01*
G01Y76728D02*
Y77200D01*
G01X1818400Y72700D02*
X1822428Y76728D01*
G01X1872298Y68922D02*
X1868600D01*
G01X1872900Y45750D02*
Y49000D01*
G01X1834600Y80800D02*
X1818200Y64400D01*
G01X1834600Y110300D02*
Y80800D01*
G01X1865500Y30050D02*
X1862300D01*
G01X1866750Y31300D02*
X1865500Y30050D01*
G01X1868800Y31300D02*
X1866750D01*
G01X1867450Y36850D02*
Y38100D01*
G01X1864800Y34200D02*
X1867450Y36850D01*
G01X1862900Y34200D02*
X1864800D01*
G01X1867450Y62550D02*
Y42100D01*
G01X1856000Y74000D02*
X1867450Y62550D01*
G01X1856000Y85500D02*
Y74000D01*
G01X1867450Y38100D02*
Y42100D01*
G01X1862300Y33600D02*
X1862900Y34200D01*
G01X1862300Y30050D02*
Y33600D01*
G01X1818900Y88800D02*
Y94400D01*
G01X1818928Y88772D02*
X1818900Y88800D01*
G01X1818928Y85039D02*
Y88772D01*
G01Y80939D02*
Y85039D01*
G01X1838450Y20700D02*
X1835000D01*
G01X1838850Y21100D02*
X1838450Y20700D01*
G01X1830950Y19950D02*
Y20900D01*
G01X1823975Y12975D02*
X1830950Y19950D01*
G01X1834800Y20900D02*
X1835000Y20700D01*
G01X1830950Y20900D02*
X1834800D01*
G01X1838550Y25500D02*
X1835000D01*
G01X1838850Y25200D02*
X1838550Y25500D01*
G01X1831350D02*
X1830950Y25100D01*
G01X1835000Y25500D02*
X1831350D01*
G01X1830288Y25762D02*
X1830950Y25100D01*
G01X1830288Y26277D02*
Y25762D01*
G01X1828627Y27938D02*
X1830288Y26277D01*
G01X1824724Y27938D02*
X1828627D01*
G01X1824561Y27775D02*
X1824724Y27938D01*
G01X1823439Y27775D02*
X1824561D01*
G01X1819841Y24177D02*
X1823439Y27775D01*
G01X1819841Y19277D02*
Y24177D01*
G01X1877500Y25250D02*
X1878600Y24150D01*
G01X1874900Y25250D02*
X1877500D01*
G01X1882150Y24150D02*
X1878600D01*
G01X1883500Y25500D02*
X1882150Y24150D01*
G01X1883500Y29300D02*
Y25500D01*
G01X1899819Y126319D02*
X1909941D01*
G01X1885000Y111500D02*
X1899819Y126319D01*
G01X1864000Y113000D02*
X1861000Y110000D01*
G01X1865500Y113000D02*
X1864000D01*
G01X1832838Y112062D02*
X1834600Y110300D01*
G01X1832838Y134060D02*
Y112062D01*
G01X1834018Y135240D02*
X1832838Y134060D01*
G01X1834018Y169783D02*
Y135240D01*
G01X1825850Y101000D02*
X1825650Y100800D01*
G01X1830000Y101000D02*
X1825850D01*
G01X1830750Y101750D02*
Y109500D01*
G01X1830000Y101000D02*
X1830750Y101750D01*
G01Y116750D02*
Y113500D01*
G01X1829500Y118000D02*
X1830750Y116750D01*
G01X1829500Y120000D02*
Y118000D01*
G01X1830750Y109500D02*
Y113500D01*
G01X1825650Y98650D02*
Y100800D01*
G01X1827900Y96400D02*
X1825650Y98650D01*
G01X1827900Y94400D02*
Y96400D01*
G01X1900319Y156319D02*
X1909941D01*
G01X1893600Y149600D02*
X1900319Y156319D01*
G01X1878100Y149600D02*
X1893600D01*
G01X1818900Y97550D02*
X1822150Y100800D01*
G01X1818900Y94400D02*
Y97550D01*
G01X1819875Y403559D02*
Y396850D01*
G01Y406013D02*
Y403559D01*
G01X1817343Y408545D02*
X1819875Y406013D01*
G01X1829250Y527250D02*
Y533500D01*
G01X1829000Y527000D02*
X1829250Y527250D01*
G01X1834500Y559750D02*
X1831750Y562500D01*
G01X1834500Y535000D02*
Y559750D01*
G01X1833000Y533500D02*
X1834500Y535000D01*
G01X1831750Y569500D02*
Y566500D01*
G01X1830000Y571250D02*
X1831750Y569500D01*
G01Y562500D02*
Y566500D01*
G01X1829250Y533500D02*
X1833000D01*
G01X1863000Y517500D02*
Y510750D01*
G01X1864500Y519000D02*
X1863000Y517500D01*
G01X1866700Y519000D02*
X1864500D01*
G01X1848500Y510750D02*
X1853000D01*
G01D02*
X1858000D01*
G01X1863000D02*
X1858000D01*
G01X1853250Y522200D02*
Y527000D01*
G01X1856450Y519000D02*
X1853250Y522200D01*
G01X1859300Y519000D02*
X1856450D01*
G01X1848500Y507250D02*
Y504000D01*
G01X1818500Y517250D02*
X1818250Y517000D01*
G01X1857500Y558000D02*
Y564000D01*
G01X1851750Y544250D02*
X1849500Y542000D01*
G01X1851750Y549000D02*
Y544250D01*
G01X1852500Y553000D02*
X1857500Y558000D01*
G01X1851750Y553000D02*
X1852500D01*
G01X1851750Y549000D02*
Y553000D01*
G01X1848750Y541250D02*
X1843000D01*
G01X1849500Y542000D02*
X1848750Y541250D01*
G01X1876100Y525900D02*
X1876150Y525950D01*
G01X1876100Y521200D02*
Y525900D01*
G01X1876150Y525950D02*
Y530600D01*
G01X1885500Y565000D02*
X1899575Y579075D01*
G01X1885500Y539324D02*
Y565000D01*
G01X1883630Y537454D02*
X1885500Y539324D01*
G01X1879004Y537454D02*
X1883630D01*
G01X1876150Y534600D02*
X1879004Y537454D01*
G01X1876150Y530600D02*
Y534600D01*
G01X1860109Y497977D02*
X1843241Y481109D01*
G01X1876100Y513968D02*
X1860109Y497977D01*
G01X1876100Y515200D02*
Y513968D01*
G01X1859250Y543500D02*
Y531162D01*
G01Y527743D02*
Y531162D01*
G01X1862500Y524493D02*
X1859250Y527743D01*
G01X1862500Y522500D02*
Y524493D01*
G01X1863440Y521560D02*
X1862500Y522500D01*
G01X1866700Y521560D02*
X1863440D01*
G01X1859250Y550750D02*
Y547500D01*
G01X1865500Y557000D02*
X1859250Y550750D01*
G01X1865500Y566000D02*
Y557000D01*
G01X1859250Y547500D02*
Y543500D01*
G01X1818500Y504750D02*
X1822000D01*
G01X1825750Y533500D02*
X1821000D01*
G01X1818500Y520750D02*
X1823000D01*
G01Y524000D02*
X1820000Y527000D01*
G01X1823000Y520750D02*
Y524000D01*
G01X1820000Y532500D02*
X1821000Y533500D01*
G01X1820000Y527000D02*
Y532500D01*
G01X1851310Y516440D02*
X1849750Y518000D01*
G01X1859300Y516440D02*
X1851310D01*
G01X1843250Y537500D02*
Y533500D01*
G01X1843000Y537750D02*
X1843250Y537500D01*
G01X1849750Y527000D02*
Y518000D01*
G01Y532750D02*
X1849500Y533000D01*
G01X1849750Y527000D02*
Y532750D01*
G01X1843750Y533000D02*
X1843250Y533500D01*
G01X1849500Y533000D02*
X1843750D01*
G01X1830000Y573000D02*
Y571250D01*
G01X1900575Y609075D02*
X1909941D01*
G01X1894400Y602900D02*
X1900575Y609075D01*
G01X1878200Y602900D02*
X1894400D01*
G01X1899575Y579075D02*
X1909941D01*
G01X1827214Y849488D02*
Y689076D01*
G01X1838174Y829350D02*
Y825000D01*
G01Y842032D02*
Y836182D01*
G01D02*
Y829350D01*
G01X1839651Y861925D02*
X1827214Y849488D01*
G01X1852907Y855959D02*
Y860061D01*
G01Y855959D02*
Y849250D01*
G01X1861278Y943500D02*
X1866318Y948540D01*
G01X1869689Y951911D02*
X1866318Y948540D01*
G01X1869689Y965758D02*
Y951911D01*
G01X1827700Y940200D02*
X1848500D01*
G01X1851043Y861925D02*
X1839651D01*
G01X1852907Y860061D02*
X1851043Y861925D01*
G01X1818500Y957250D02*
X1822000D01*
G01X1834500Y986500D02*
X1834000Y986000D01*
G01X1834500Y1012250D02*
Y986500D01*
G01X1831750Y1015000D02*
X1834500Y1012250D01*
G01X1829250Y979750D02*
Y986000D01*
G01X1829000Y979500D02*
X1829250Y979750D01*
G01X1831750Y1022000D02*
Y1019000D01*
G01X1830000Y1023750D02*
X1831750Y1022000D01*
G01X1830000Y1025500D02*
Y1023750D01*
G01X1831750Y1019000D02*
Y1015000D01*
G01X1829250Y986000D02*
X1834000D01*
G01X1851310Y969440D02*
X1849750Y971000D01*
G01X1859300Y969440D02*
X1851310D01*
G01X1843250Y990500D02*
Y986500D01*
G01X1843000Y990750D02*
X1843250Y990500D01*
G01X1849750Y980000D02*
Y971000D01*
G01Y985750D02*
X1849500Y986000D01*
G01X1849750Y980000D02*
Y985750D01*
G01X1843750Y986000D02*
X1843250Y986500D01*
G01X1849500Y986000D02*
X1843750D01*
G01X1873700Y969769D02*
X1869689Y965758D01*
G01X1873700Y976000D02*
Y969769D01*
G01X1867500Y982200D02*
X1873700Y976000D01*
G01X1848500Y960250D02*
Y957000D01*
G01X1863000Y970500D02*
Y963750D01*
G01X1864611Y972111D02*
X1863000Y970500D01*
G01X1866589Y972111D02*
X1864611D01*
G01X1866700Y972000D02*
X1866589Y972111D01*
G01X1858000Y963750D02*
X1853000D01*
G01D02*
X1848500D01*
G01X1863000D02*
X1858000D01*
G01X1859250Y996500D02*
Y983276D01*
G01Y981250D02*
Y983276D01*
G01X1862500Y978000D02*
X1859250Y981250D01*
G01X1862500Y976000D02*
Y978000D01*
G01X1863940Y974560D02*
X1862500Y976000D01*
G01X1866700Y974560D02*
X1863940D01*
G01X1859250Y1003750D02*
Y1000500D01*
G01X1865500Y1010000D02*
X1859250Y1003750D01*
G01X1865500Y1019000D02*
Y1010000D01*
G01X1859250Y1000500D02*
Y996500D01*
G01X1867500Y988200D02*
X1871900D01*
G01X1875750D02*
X1875800Y988250D01*
G01X1871900Y988200D02*
X1875750D01*
G01X1899331Y1031831D02*
X1909941D01*
G01X1885000Y1017500D02*
X1899331Y1031831D01*
G01X1885000Y991250D02*
Y1017500D01*
G01X1882000Y988250D02*
X1885000Y991250D01*
G01X1879800Y988250D02*
X1882000D01*
G01X1875800D02*
X1879800D01*
G01X1853250Y975200D02*
Y980000D01*
G01X1856450Y972000D02*
X1853250Y975200D01*
G01X1859300Y972000D02*
X1856450D01*
G01X1857500Y1017000D02*
Y1010000D01*
G01X1851750Y997250D02*
X1849500Y995000D01*
G01X1851750Y1002000D02*
Y997250D01*
G01X1853500Y1006000D02*
X1851750D01*
G01X1857500Y1010000D02*
X1853500Y1006000D01*
G01X1851750Y1002000D02*
Y1006000D01*
G01X1848750Y994250D02*
X1843000D01*
G01X1849500Y995000D02*
X1848750Y994250D01*
G01X1818500Y969750D02*
X1818250Y969500D01*
G01X1825750Y986000D02*
X1821000D01*
G01X1818500Y973250D02*
X1823000D01*
G01Y976500D02*
X1820000Y979500D01*
G01X1823000Y973250D02*
Y976500D01*
G01X1820000Y985000D02*
X1821000Y986000D01*
G01X1820000Y979500D02*
Y985000D01*
G01X1900331Y1061831D02*
X1909941D01*
G01X1894600Y1056100D02*
X1900331Y1061831D01*
G01X1878300Y1056100D02*
X1894600D01*
M02*
